FILE_TYPE = MACRO_DRAWING;
SET COLOR_WIRE YELLOW;
SET COLOR_PROP ORANGE;
SET COLOR_DOT WHITE;
SET COLOR_ARC YELLOW;
SET COLOR_BODY GREEN;
SET COLOR_NOTE PURPLE;
SET PROP_DISPLAY VALUE;
SET PAGE_NUMBER P45;
FORCEADD GENOA_SP5..9
(-4500 3575);
FORCEPROP 1 LAST LOCATION U26
J 0
(-5145 6406);
DISPLAY 0.489362 (-5145 6406);
PAINT SKYBLUE (-5145 6406);
FORCEPROP 0 LAST $SEC 9
J 0
(-5125 6450);
DISPLAY 0.680851 (-5125 6450);
PAINT MONO (-5125 6450);
DISPLAY INVISIBLE (-5125 6450);
FORCEPROP 0 LAST CDS_SEC 9
J 0
(-5125 6400);
DISPLAY 1.021277 (-5125 6400);
DISPLAY INVISIBLE (-5125 6400);
FORCEPROP 0 LASTPIN (-5300 2950) $PN BC19
J 2
(-5310 2960);
DISPLAY 0.489362 (-5310 2960);
PAINT MONO (-5310 2960);
FORCEPROP 0 LASTPIN (-5300 2900) $PN BD20
J 2
(-5310 2910);
DISPLAY 0.489362 (-5310 2910);
PAINT MONO (-5310 2910);
FORCEPROP 0 LASTPIN (-5300 1800) $PN BF20
J 2
(-5310 1810);
DISPLAY 0.489362 (-5310 1810);
PAINT MONO (-5310 1810);
FORCEPROP 0 LASTPIN (-5300 1750) $PN BG19
J 2
(-5310 1760);
DISPLAY 0.489362 (-5310 1760);
PAINT MONO (-5310 1760);
FORCEPROP 0 LASTPIN (-5300 2100) $PN AT21
J 2
(-5310 2110);
DISPLAY 0.489362 (-5310 2110);
PAINT MONO (-5310 2110);
FORCEPROP 0 LASTPIN (-5300 2000) $PN AU21
J 2
(-5310 2010);
DISPLAY 0.489362 (-5310 2010);
PAINT MONO (-5310 2010);
FORCEPROP 0 LASTPIN (-5300 2800) $PN AU19
J 2
(-5310 2810);
DISPLAY 0.489362 (-5310 2810);
PAINT MONO (-5310 2810);
FORCEPROP 0 LASTPIN (-5300 2750) $PN AV21
J 2
(-5310 2760);
DISPLAY 0.489362 (-5310 2760);
PAINT MONO (-5310 2760);
FORCEPROP 0 LASTPIN (-5300 2650) $PN BN21
J 2
(-5310 2660);
DISPLAY 0.489362 (-5310 2660);
PAINT MONO (-5310 2660);
FORCEPROP 0 LASTPIN (-5300 1650) $PN AV20
J 2
(-5310 1660);
DISPLAY 0.489362 (-5310 1660);
PAINT MONO (-5310 1660);
FORCEPROP 0 LASTPIN (-5300 1600) $PN AW21
J 2
(-5310 1610);
DISPLAY 0.489362 (-5310 1610);
PAINT MONO (-5310 1610);
FORCEPROP 0 LASTPIN (-5300 1500) $PN BP21
J 2
(-5310 1510);
DISPLAY 0.489362 (-5310 1510);
PAINT MONO (-5310 1510);
FORCEPROP 0 LASTPIN (-5300 3800) $PN AW19
J 2
(-5310 3810);
DISPLAY 0.489362 (-5310 3810);
PAINT MONO (-5310 3810);
FORCEPROP 0 LASTPIN (-5300 3750) $PN AY20
J 2
(-5310 3760);
DISPLAY 0.489362 (-5310 3760);
PAINT MONO (-5310 3760);
FORCEPROP 0 LASTPIN (-5300 3700) $PN AY21
J 2
(-5310 3710);
DISPLAY 0.489362 (-5310 3710);
PAINT MONO (-5310 3710);
FORCEPROP 0 LASTPIN (-5300 3650) $PN BA21
J 2
(-5310 3660);
DISPLAY 0.489362 (-5310 3660);
PAINT MONO (-5310 3660);
FORCEPROP 0 LASTPIN (-5300 3600) $PN BA19
J 2
(-5310 3610);
DISPLAY 0.489362 (-5310 3610);
PAINT MONO (-5310 3610);
FORCEPROP 0 LASTPIN (-5300 3550) $PN BB20
J 2
(-5310 3560);
DISPLAY 0.489362 (-5310 3560);
PAINT MONO (-5310 3560);
FORCEPROP 0 LASTPIN (-5300 3500) $PN BB21
J 2
(-5310 3510);
DISPLAY 0.489362 (-5310 3510);
PAINT MONO (-5310 3510);
FORCEPROP 0 LASTPIN (-3700 2350) $PN AJ19
J 0
(-3690 2360);
DISPLAY 0.489362 (-3690 2360);
PAINT MONO (-3690 2360);
FORCEPROP 0 LASTPIN (-3700 2300) $PN AK21
J 0
(-3690 2310);
DISPLAY 0.489362 (-3690 2310);
PAINT MONO (-3690 2310);
FORCEPROP 0 LASTPIN (-3700 2250) $PN AK20
J 0
(-3690 2260);
DISPLAY 0.489362 (-3690 2260);
PAINT MONO (-3690 2260);
FORCEPROP 0 LASTPIN (-3700 2200) $PN AL21
J 0
(-3690 2210);
DISPLAY 0.489362 (-3690 2210);
PAINT MONO (-3690 2210);
FORCEPROP 0 LASTPIN (-3700 2150) $PN AN19
J 0
(-3690 2160);
DISPLAY 0.489362 (-3690 2160);
PAINT MONO (-3690 2160);
FORCEPROP 0 LASTPIN (-3700 2100) $PN AP21
J 0
(-3690 2110);
DISPLAY 0.489362 (-3690 2110);
PAINT MONO (-3690 2110);
FORCEPROP 0 LASTPIN (-3700 2050) $PN AP20
J 0
(-3690 2060);
DISPLAY 0.489362 (-3690 2060);
PAINT MONO (-3690 2060);
FORCEPROP 0 LASTPIN (-3700 2000) $PN AR21
J 0
(-3690 2010);
DISPLAY 0.489362 (-3690 2010);
PAINT MONO (-3690 2010);
FORCEPROP 0 LASTPIN (-3700 5950) $PN E19
J 0
(-3690 5960);
DISPLAY 0.489362 (-3690 5960);
PAINT MONO (-3690 5960);
FORCEPROP 0 LASTPIN (-3700 5900) $PN F21
J 0
(-3690 5910);
DISPLAY 0.489362 (-3690 5910);
PAINT MONO (-3690 5910);
FORCEPROP 0 LASTPIN (-3700 5850) $PN F20
J 0
(-3690 5860);
DISPLAY 0.489362 (-3690 5860);
PAINT MONO (-3690 5860);
FORCEPROP 0 LASTPIN (-3700 5800) $PN G21
J 0
(-3690 5810);
DISPLAY 0.489362 (-3690 5810);
PAINT MONO (-3690 5810);
FORCEPROP 0 LASTPIN (-3700 5750) $PN J19
J 0
(-3690 5760);
DISPLAY 0.489362 (-3690 5760);
PAINT MONO (-3690 5760);
FORCEPROP 0 LASTPIN (-3700 5700) $PN K21
J 0
(-3690 5710);
DISPLAY 0.489362 (-3690 5710);
PAINT MONO (-3690 5710);
FORCEPROP 0 LASTPIN (-3700 5650) $PN K20
J 0
(-3690 5660);
DISPLAY 0.489362 (-3690 5660);
PAINT MONO (-3690 5660);
FORCEPROP 0 LASTPIN (-3700 5600) $PN L21
J 0
(-3690 5610);
DISPLAY 0.489362 (-3690 5610);
PAINT MONO (-3690 5610);
FORCEPROP 0 LASTPIN (-3700 5500) $PN L19
J 0
(-3690 5510);
DISPLAY 0.489362 (-3690 5510);
PAINT MONO (-3690 5510);
FORCEPROP 0 LASTPIN (-3700 5450) $PN M21
J 0
(-3690 5460);
DISPLAY 0.489362 (-3690 5460);
PAINT MONO (-3690 5460);
FORCEPROP 0 LASTPIN (-3700 5400) $PN M20
J 0
(-3690 5410);
DISPLAY 0.489362 (-3690 5410);
PAINT MONO (-3690 5410);
FORCEPROP 0 LASTPIN (-3700 5350) $PN N21
J 0
(-3690 5360);
DISPLAY 0.489362 (-3690 5360);
PAINT MONO (-3690 5360);
FORCEPROP 0 LASTPIN (-3700 5300) $PN R19
J 0
(-3690 5310);
DISPLAY 0.489362 (-3690 5310);
PAINT MONO (-3690 5310);
FORCEPROP 0 LASTPIN (-3700 5250) $PN T21
J 0
(-3690 5260);
DISPLAY 0.489362 (-3690 5260);
PAINT MONO (-3690 5260);
FORCEPROP 0 LASTPIN (-3700 5200) $PN T20
J 0
(-3690 5210);
DISPLAY 0.489362 (-3690 5210);
PAINT MONO (-3690 5210);
FORCEPROP 0 LASTPIN (-3700 5150) $PN U21
J 0
(-3690 5160);
DISPLAY 0.489362 (-3690 5160);
PAINT MONO (-3690 5160);
FORCEPROP 0 LASTPIN (-3700 5050) $PN U19
J 0
(-3690 5060);
DISPLAY 0.489362 (-3690 5060);
PAINT MONO (-3690 5060);
FORCEPROP 0 LASTPIN (-3700 5000) $PN V21
J 0
(-3690 5010);
DISPLAY 0.489362 (-3690 5010);
PAINT MONO (-3690 5010);
FORCEPROP 0 LASTPIN (-3700 4950) $PN V20
J 0
(-3690 4960);
DISPLAY 0.489362 (-3690 4960);
PAINT MONO (-3690 4960);
FORCEPROP 0 LASTPIN (-3700 4900) $PN W21
J 0
(-3690 4910);
DISPLAY 0.489362 (-3690 4910);
PAINT MONO (-3690 4910);
FORCEPROP 0 LASTPIN (-3700 4850) $PN AA19
J 0
(-3690 4860);
DISPLAY 0.489362 (-3690 4860);
PAINT MONO (-3690 4860);
FORCEPROP 0 LASTPIN (-3700 4800) $PN AB21
J 0
(-3690 4810);
DISPLAY 0.489362 (-3690 4810);
PAINT MONO (-3690 4810);
FORCEPROP 0 LASTPIN (-3700 4750) $PN AB20
J 0
(-3690 4760);
DISPLAY 0.489362 (-3690 4760);
PAINT MONO (-3690 4760);
FORCEPROP 0 LASTPIN (-3700 4700) $PN AC21
J 0
(-3690 4710);
DISPLAY 0.489362 (-3690 4710);
PAINT MONO (-3690 4710);
FORCEPROP 0 LASTPIN (-3700 4600) $PN AC19
J 0
(-3690 4610);
DISPLAY 0.489362 (-3690 4610);
PAINT MONO (-3690 4610);
FORCEPROP 0 LASTPIN (-3700 4550) $PN AD21
J 0
(-3690 4560);
DISPLAY 0.489362 (-3690 4560);
PAINT MONO (-3690 4560);
FORCEPROP 0 LASTPIN (-3700 4500) $PN AD20
J 0
(-3690 4510);
DISPLAY 0.489362 (-3690 4510);
PAINT MONO (-3690 4510);
FORCEPROP 0 LASTPIN (-3700 4450) $PN AE21
J 0
(-3690 4460);
DISPLAY 0.489362 (-3690 4460);
PAINT MONO (-3690 4460);
FORCEPROP 0 LASTPIN (-3700 4400) $PN AG19
J 0
(-3690 4410);
DISPLAY 0.489362 (-3690 4410);
PAINT MONO (-3690 4410);
FORCEPROP 0 LASTPIN (-3700 4350) $PN AH21
J 0
(-3690 4360);
DISPLAY 0.489362 (-3690 4360);
PAINT MONO (-3690 4360);
FORCEPROP 0 LASTPIN (-3700 4300) $PN AH20
J 0
(-3690 4310);
DISPLAY 0.489362 (-3690 4310);
PAINT MONO (-3690 4310);
FORCEPROP 0 LASTPIN (-3700 4250) $PN AJ21
J 0
(-3690 4260);
DISPLAY 0.489362 (-3690 4260);
PAINT MONO (-3690 4260);
FORCEPROP 0 LASTPIN (-5300 5950) $PN G19
J 2
(-5310 5960);
DISPLAY 0.489362 (-5310 5960);
PAINT MONO (-5310 5960);
FORCEPROP 0 LASTPIN (-5300 5850) $PN N19
J 2
(-5310 5860);
DISPLAY 0.489362 (-5310 5860);
PAINT MONO (-5310 5860);
FORCEPROP 0 LASTPIN (-5300 5750) $PN W19
J 2
(-5310 5760);
DISPLAY 0.489362 (-5310 5760);
PAINT MONO (-5310 5760);
FORCEPROP 0 LASTPIN (-5300 5650) $PN AE19
J 2
(-5310 5660);
DISPLAY 0.489362 (-5310 5660);
PAINT MONO (-5310 5660);
FORCEPROP 0 LASTPIN (-5300 5550) $PN AL19
J 2
(-5310 5560);
DISPLAY 0.489362 (-5310 5560);
PAINT MONO (-5310 5560);
FORCEPROP 0 LASTPIN (-5300 5450) $PN J21
J 2
(-5310 5460);
DISPLAY 0.489362 (-5310 5460);
PAINT MONO (-5310 5460);
FORCEPROP 0 LASTPIN (-5300 5350) $PN R21
J 2
(-5310 5360);
DISPLAY 0.489362 (-5310 5360);
PAINT MONO (-5310 5360);
FORCEPROP 0 LASTPIN (-5300 5250) $PN AA21
J 2
(-5310 5260);
DISPLAY 0.489362 (-5310 5260);
PAINT MONO (-5310 5260);
FORCEPROP 0 LASTPIN (-5300 5150) $PN AG21
J 2
(-5310 5160);
DISPLAY 0.489362 (-5310 5160);
PAINT MONO (-5310 5160);
FORCEPROP 0 LASTPIN (-5300 5050) $PN AN21
J 2
(-5310 5060);
DISPLAY 0.489362 (-5310 5060);
PAINT MONO (-5310 5060);
FORCEPROP 0 LASTPIN (-5300 5900) $PN H20
J 2
(-5310 5910);
DISPLAY 0.489362 (-5310 5910);
PAINT MONO (-5310 5910);
FORCEPROP 0 LASTPIN (-5300 5800) $PN P20
J 2
(-5310 5810);
DISPLAY 0.489362 (-5310 5810);
PAINT MONO (-5310 5810);
FORCEPROP 0 LASTPIN (-5300 5700) $PN Y20
J 2
(-5310 5710);
DISPLAY 0.489362 (-5310 5710);
PAINT MONO (-5310 5710);
FORCEPROP 0 LASTPIN (-5300 5600) $PN AF20
J 2
(-5310 5610);
DISPLAY 0.489362 (-5310 5610);
PAINT MONO (-5310 5610);
FORCEPROP 0 LASTPIN (-5300 5500) $PN AM20
J 2
(-5310 5510);
DISPLAY 0.489362 (-5310 5510);
PAINT MONO (-5310 5510);
FORCEPROP 0 LASTPIN (-5300 5400) $PN H21
J 2
(-5310 5410);
DISPLAY 0.489362 (-5310 5410);
PAINT MONO (-5310 5410);
FORCEPROP 0 LASTPIN (-5300 5300) $PN P21
J 2
(-5310 5310);
DISPLAY 0.489362 (-5310 5310);
PAINT MONO (-5310 5310);
FORCEPROP 0 LASTPIN (-5300 5200) $PN Y21
J 2
(-5310 5210);
DISPLAY 0.489362 (-5310 5210);
PAINT MONO (-5310 5210);
FORCEPROP 0 LASTPIN (-5300 5100) $PN AF21
J 2
(-5310 5110);
DISPLAY 0.489362 (-5310 5110);
PAINT MONO (-5310 5110);
FORCEPROP 0 LASTPIN (-5300 5000) $PN AM21
J 2
(-5310 5010);
DISPLAY 0.489362 (-5310 5010);
PAINT MONO (-5310 5010);
FORCEPROP 0 LASTPIN (-5300 2550) $PN BC21
J 2
(-5310 2560);
DISPLAY 0.489362 (-5310 2560);
PAINT MONO (-5310 2560);
FORCEPROP 0 LASTPIN (-5300 2450) $PN BM21
J 2
(-5310 2460);
DISPLAY 0.489362 (-5310 2460);
PAINT MONO (-5310 2460);
FORCEPROP 0 LASTPIN (-5300 2400) $PN BN19
J 2
(-5310 2410);
DISPLAY 0.489362 (-5310 2410);
PAINT MONO (-5310 2410);
FORCEPROP 0 LASTPIN (-5300 2300) $PN BP20
J 2
(-5310 2310);
DISPLAY 0.489362 (-5310 2310);
PAINT MONO (-5310 2310);
FORCEPROP 0 LASTPIN (-5300 1400) $PN BL19
J 2
(-5310 1410);
DISPLAY 0.489362 (-5310 1410);
PAINT MONO (-5310 1410);
FORCEPROP 0 LASTPIN (-5300 1350) $PN BM20
J 2
(-5310 1360);
DISPLAY 0.489362 (-5310 1360);
PAINT MONO (-5310 1360);
FORCEPROP 0 LASTPIN (-5300 1250) $PN BR19
J 2
(-5310 1260);
DISPLAY 0.489362 (-5310 1260);
PAINT MONO (-5310 1260);
FORCEPROP 0 LASTPIN (-5300 3400) $PN BG21
J 2
(-5310 3410);
DISPLAY 0.489362 (-5310 3410);
PAINT MONO (-5310 3410);
FORCEPROP 0 LASTPIN (-5300 3350) $PN BH21
J 2
(-5310 3360);
DISPLAY 0.489362 (-5310 3360);
PAINT MONO (-5310 3360);
FORCEPROP 0 LASTPIN (-5300 3300) $PN BH20
J 2
(-5310 3310);
DISPLAY 0.489362 (-5310 3310);
PAINT MONO (-5310 3310);
FORCEPROP 0 LASTPIN (-5300 3250) $PN BJ19
J 2
(-5310 3260);
DISPLAY 0.489362 (-5310 3260);
PAINT MONO (-5310 3260);
FORCEPROP 0 LASTPIN (-5300 3200) $PN BJ21
J 2
(-5310 3210);
DISPLAY 0.489362 (-5310 3210);
PAINT MONO (-5310 3210);
FORCEPROP 0 LASTPIN (-5300 3150) $PN BK21
J 2
(-5310 3160);
DISPLAY 0.489362 (-5310 3160);
PAINT MONO (-5310 3160);
FORCEPROP 0 LASTPIN (-5300 3100) $PN BK20
J 2
(-5310 3110);
DISPLAY 0.489362 (-5310 3110);
PAINT MONO (-5310 3110);
FORCEPROP 0 LASTPIN (-3700 1900) $PN BY20
J 0
(-3690 1910);
DISPLAY 0.489362 (-3690 1910);
PAINT MONO (-3690 1910);
FORCEPROP 0 LASTPIN (-3700 1850) $PN CA21
J 0
(-3690 1860);
DISPLAY 0.489362 (-3690 1860);
PAINT MONO (-3690 1860);
FORCEPROP 0 LASTPIN (-3700 1800) $PN CA19
J 0
(-3690 1810);
DISPLAY 0.489362 (-3690 1810);
PAINT MONO (-3690 1810);
FORCEPROP 0 LASTPIN (-3700 1750) $PN CB21
J 0
(-3690 1760);
DISPLAY 0.489362 (-3690 1760);
PAINT MONO (-3690 1760);
FORCEPROP 0 LASTPIN (-3700 1700) $PN BT20
J 0
(-3690 1710);
DISPLAY 0.489362 (-3690 1710);
PAINT MONO (-3690 1710);
FORCEPROP 0 LASTPIN (-3700 1650) $PN BU21
J 0
(-3690 1660);
DISPLAY 0.489362 (-3690 1660);
PAINT MONO (-3690 1660);
FORCEPROP 0 LASTPIN (-3700 1600) $PN BU19
J 0
(-3690 1610);
DISPLAY 0.489362 (-3690 1610);
PAINT MONO (-3690 1610);
FORCEPROP 0 LASTPIN (-3700 1550) $PN BV21
J 0
(-3690 1560);
DISPLAY 0.489362 (-3690 1560);
PAINT MONO (-3690 1560);
FORCEPROP 0 LASTPIN (-3700 4150) $PN CB20
J 0
(-3690 4160);
DISPLAY 0.489362 (-3690 4160);
PAINT MONO (-3690 4160);
FORCEPROP 0 LASTPIN (-3700 4100) $PN CC21
J 0
(-3690 4110);
DISPLAY 0.489362 (-3690 4110);
PAINT MONO (-3690 4110);
FORCEPROP 0 LASTPIN (-3700 4050) $PN CC19
J 0
(-3690 4060);
DISPLAY 0.489362 (-3690 4060);
PAINT MONO (-3690 4060);
FORCEPROP 0 LASTPIN (-3700 4000) $PN CD21
J 0
(-3690 4010);
DISPLAY 0.489362 (-3690 4010);
PAINT MONO (-3690 4010);
FORCEPROP 0 LASTPIN (-3700 3950) $PN CF20
J 0
(-3690 3960);
DISPLAY 0.489362 (-3690 3960);
PAINT MONO (-3690 3960);
FORCEPROP 0 LASTPIN (-3700 3900) $PN CG21
J 0
(-3690 3910);
DISPLAY 0.489362 (-3690 3910);
PAINT MONO (-3690 3910);
FORCEPROP 0 LASTPIN (-3700 3850) $PN CG19
J 0
(-3690 3860);
DISPLAY 0.489362 (-3690 3860);
PAINT MONO (-3690 3860);
FORCEPROP 0 LASTPIN (-3700 3800) $PN CH21
J 0
(-3690 3810);
DISPLAY 0.489362 (-3690 3810);
PAINT MONO (-3690 3810);
FORCEPROP 0 LASTPIN (-3700 3700) $PN CH20
J 0
(-3690 3710);
DISPLAY 0.489362 (-3690 3710);
PAINT MONO (-3690 3710);
FORCEPROP 0 LASTPIN (-3700 3650) $PN CJ21
J 0
(-3690 3660);
DISPLAY 0.489362 (-3690 3660);
PAINT MONO (-3690 3660);
FORCEPROP 0 LASTPIN (-3700 3600) $PN CJ19
J 0
(-3690 3610);
DISPLAY 0.489362 (-3690 3610);
PAINT MONO (-3690 3610);
FORCEPROP 0 LASTPIN (-3700 3550) $PN CK21
J 0
(-3690 3560);
DISPLAY 0.489362 (-3690 3560);
PAINT MONO (-3690 3560);
FORCEPROP 0 LASTPIN (-3700 3500) $PN CM20
J 0
(-3690 3510);
DISPLAY 0.489362 (-3690 3510);
PAINT MONO (-3690 3510);
FORCEPROP 0 LASTPIN (-3700 3450) $PN CN21
J 0
(-3690 3460);
DISPLAY 0.489362 (-3690 3460);
PAINT MONO (-3690 3460);
FORCEPROP 0 LASTPIN (-3700 3400) $PN CN19
J 0
(-3690 3410);
DISPLAY 0.489362 (-3690 3410);
PAINT MONO (-3690 3410);
FORCEPROP 0 LASTPIN (-3700 3350) $PN CP21
J 0
(-3690 3360);
DISPLAY 0.489362 (-3690 3360);
PAINT MONO (-3690 3360);
FORCEPROP 0 LASTPIN (-3700 3250) $PN CP20
J 0
(-3690 3260);
DISPLAY 0.489362 (-3690 3260);
PAINT MONO (-3690 3260);
FORCEPROP 0 LASTPIN (-3700 3200) $PN CR21
J 0
(-3690 3210);
DISPLAY 0.489362 (-3690 3210);
PAINT MONO (-3690 3210);
FORCEPROP 0 LASTPIN (-3700 3150) $PN CR19
J 0
(-3690 3160);
DISPLAY 0.489362 (-3690 3160);
PAINT MONO (-3690 3160);
FORCEPROP 0 LASTPIN (-3700 3100) $PN CT21
J 0
(-3690 3110);
DISPLAY 0.489362 (-3690 3110);
PAINT MONO (-3690 3110);
FORCEPROP 0 LASTPIN (-3700 3050) $PN CV20
J 0
(-3690 3060);
DISPLAY 0.489362 (-3690 3060);
PAINT MONO (-3690 3060);
FORCEPROP 0 LASTPIN (-3700 3000) $PN CW21
J 0
(-3690 3010);
DISPLAY 0.489362 (-3690 3010);
PAINT MONO (-3690 3010);
FORCEPROP 0 LASTPIN (-3700 2950) $PN CW19
J 0
(-3690 2960);
DISPLAY 0.489362 (-3690 2960);
PAINT MONO (-3690 2960);
FORCEPROP 0 LASTPIN (-3700 2900) $PN CY21
J 0
(-3690 2910);
DISPLAY 0.489362 (-3690 2910);
PAINT MONO (-3690 2910);
FORCEPROP 0 LASTPIN (-3700 2800) $PN CY20
J 0
(-3690 2810);
DISPLAY 0.489362 (-3690 2810);
PAINT MONO (-3690 2810);
FORCEPROP 0 LASTPIN (-3700 2750) $PN DA21
J 0
(-3690 2760);
DISPLAY 0.489362 (-3690 2760);
PAINT MONO (-3690 2760);
FORCEPROP 0 LASTPIN (-3700 2700) $PN DA19
J 0
(-3690 2710);
DISPLAY 0.489362 (-3690 2710);
PAINT MONO (-3690 2710);
FORCEPROP 0 LASTPIN (-3700 2650) $PN DB21
J 0
(-3690 2660);
DISPLAY 0.489362 (-3690 2660);
PAINT MONO (-3690 2660);
FORCEPROP 0 LASTPIN (-3700 2600) $PN DD20
J 0
(-3690 2610);
DISPLAY 0.489362 (-3690 2610);
PAINT MONO (-3690 2610);
FORCEPROP 0 LASTPIN (-3700 2550) $PN DE21
J 0
(-3690 2560);
DISPLAY 0.489362 (-3690 2560);
PAINT MONO (-3690 2560);
FORCEPROP 0 LASTPIN (-3700 2500) $PN DE19
J 0
(-3690 2510);
DISPLAY 0.489362 (-3690 2510);
PAINT MONO (-3690 2510);
FORCEPROP 0 LASTPIN (-3700 2450) $PN DF21
J 0
(-3690 2460);
DISPLAY 0.489362 (-3690 2460);
PAINT MONO (-3690 2460);
FORCEPROP 0 LASTPIN (-5300 4900) $PN CD20
J 2
(-5310 4910);
DISPLAY 0.489362 (-5310 4910);
PAINT MONO (-5310 4910);
FORCEPROP 0 LASTPIN (-5300 4800) $PN CK20
J 2
(-5310 4810);
DISPLAY 0.489362 (-5310 4810);
PAINT MONO (-5310 4810);
FORCEPROP 0 LASTPIN (-5300 4700) $PN CT20
J 2
(-5310 4710);
DISPLAY 0.489362 (-5310 4710);
PAINT MONO (-5310 4710);
FORCEPROP 0 LASTPIN (-5300 4600) $PN DB20
J 2
(-5310 4610);
DISPLAY 0.489362 (-5310 4610);
PAINT MONO (-5310 4610);
FORCEPROP 0 LASTPIN (-5300 4500) $PN BY21
J 2
(-5310 4510);
DISPLAY 0.489362 (-5310 4510);
PAINT MONO (-5310 4510);
FORCEPROP 0 LASTPIN (-5300 4400) $PN CF21
J 2
(-5310 4410);
DISPLAY 0.489362 (-5310 4410);
PAINT MONO (-5310 4410);
FORCEPROP 0 LASTPIN (-5300 4300) $PN CM21
J 2
(-5310 4310);
DISPLAY 0.489362 (-5310 4310);
PAINT MONO (-5310 4310);
FORCEPROP 0 LASTPIN (-5300 4200) $PN CV21
J 2
(-5310 4210);
DISPLAY 0.489362 (-5310 4210);
PAINT MONO (-5310 4210);
FORCEPROP 0 LASTPIN (-5300 4100) $PN DD21
J 2
(-5310 4110);
DISPLAY 0.489362 (-5310 4110);
PAINT MONO (-5310 4110);
FORCEPROP 0 LASTPIN (-5300 4000) $PN BV20
J 2
(-5310 4010);
DISPLAY 0.489362 (-5310 4010);
PAINT MONO (-5310 4010);
FORCEPROP 0 LASTPIN (-5300 4850) $PN CE19
J 2
(-5310 4860);
DISPLAY 0.489362 (-5310 4860);
PAINT MONO (-5310 4860);
FORCEPROP 0 LASTPIN (-5300 4750) $PN CL19
J 2
(-5310 4760);
DISPLAY 0.489362 (-5310 4760);
PAINT MONO (-5310 4760);
FORCEPROP 0 LASTPIN (-5300 4650) $PN CU19
J 2
(-5310 4660);
DISPLAY 0.489362 (-5310 4660);
PAINT MONO (-5310 4660);
FORCEPROP 0 LASTPIN (-5300 4550) $PN DC19
J 2
(-5310 4560);
DISPLAY 0.489362 (-5310 4560);
PAINT MONO (-5310 4560);
FORCEPROP 0 LASTPIN (-5300 4450) $PN BW21
J 2
(-5310 4460);
DISPLAY 0.489362 (-5310 4460);
PAINT MONO (-5310 4460);
FORCEPROP 0 LASTPIN (-5300 4350) $PN CE21
J 2
(-5310 4360);
DISPLAY 0.489362 (-5310 4360);
PAINT MONO (-5310 4360);
FORCEPROP 0 LASTPIN (-5300 4250) $PN CL21
J 2
(-5310 4260);
DISPLAY 0.489362 (-5310 4260);
PAINT MONO (-5310 4260);
FORCEPROP 0 LASTPIN (-5300 4150) $PN CU21
J 2
(-5310 4160);
DISPLAY 0.489362 (-5310 4160);
PAINT MONO (-5310 4160);
FORCEPROP 0 LASTPIN (-5300 4050) $PN DC21
J 2
(-5310 4060);
DISPLAY 0.489362 (-5310 4060);
PAINT MONO (-5310 4060);
FORCEPROP 0 LASTPIN (-5300 3950) $PN BW19
J 2
(-5310 3960);
DISPLAY 0.489362 (-5310 3960);
PAINT MONO (-5310 3960);
FORCEPROP 0 LASTPIN (-5300 2200) $PN BL21
J 2
(-5310 2210);
DISPLAY 0.489362 (-5310 2210);
PAINT MONO (-5310 2210);
FORCEPROP 0 LASTPIN (-5300 1150) $PN BF21
J 2
(-5310 1160);
DISPLAY 0.489362 (-5310 1160);
PAINT MONO (-5310 1160);
FORCEPROP 2 LAST PART_TYPE SMLF
J 0
(-5125 6350);
DISPLAY 1.021277 (-5125 6350);
FORCEPROP 1 LAST MATERIAL IO
J 0
(-5145 6132);
DISPLAY 0.489362 (-5145 6132);
PAINT SKYBLUE (-5145 6132);
FORCEPROP 2 LAST VALUE SOCKET6096_13568-001
J 0
(-5125 6250);
DISPLAY 0.489362 (-5125 6250);
PAINT SKYBLUE (-5125 6250);
FORCEPROP 1 LAST PART_NUMBER DGA^6000030
J 0
(-5145 6259);
DISPLAY 0.489362 (-5145 6259);
PAINT SKYBLUE (-5145 6259);
FORCEPROP 1 LAST NEEDS_NO_SIZE TRUE
J 0
(-4500 3575);
DISPLAY 0.723404 (-4500 3575);
PAINT GREEN (-4500 3575);
DISPLAY INVISIBLE (-4500 3575);
FORCEPROP 1 LAST CDS_LMAN_SYM_OUTLINE -650,2525,650,-2525
J 0
(-4500 3575);
DISPLAY 0.468085 (-4500 3575);
PAINT GREEN (-4500 3575);
DISPLAY INVISIBLE (-4500 3575);
FORCEPROP 2 LAST CDS_LIB pure_quanta
J 0
(-4500 3575);
DISPLAY INVISIBLE (-4500 3575);
FORCEPROP 1 LAST PATH I159
J 0
(-4500 3575);
DISPLAY 0.723404 (-4500 3575);
PAINT GREEN (-4500 3575);
DISPLAY INVISIBLE (-4500 3575);
FORCEADD OFFPAGE..3
(-2500 5975);
FORCEPROP 2 LAST $XR0 105 
J 0
(-2286 5975);
DISPLAY 0.638298 (-2286 5975);
PAINT MONO (-2286 5975);
FORCEPROP 2 LAST PATH I160
J 0
(-2275 6025);
DISPLAY 1.021277 (-2275 6025);
DISPLAY INVISIBLE (-2275 6025);
FORCEPROP 1 LAST COMMENT_BODY TRUE
J 0
(-2550 5875);
DISPLAY 0.872340 (-2550 5875);
PAINT GREEN (-2550 5875);
DISPLAY INVISIBLE (-2550 5875);
FORCEPROP 1 LAST OFFPAGE TRUE
J 0
(-2175 5850);
DISPLAY 0.872340 (-2175 5850);
PAINT GREEN (-2175 5850);
DISPLAY INVISIBLE (-2175 5850);
FORCEPROP 2 LAST CDS_LIB mstr_standard
J 0
(-2500 5975);
DISPLAY 0.723404 (-2500 5975);
PAINT MONO (-2500 5975);
DISPLAY INVISIBLE (-2500 5975);
FORCEADD OFFPAGE..3
(-2500 4175);
FORCEPROP 2 LAST $XR0 105 
J 0
(-2286 4175);
DISPLAY 0.638298 (-2286 4175);
PAINT MONO (-2286 4175);
FORCEPROP 2 LAST PATH I161
J 0
(-2275 4225);
DISPLAY 1.021277 (-2275 4225);
DISPLAY INVISIBLE (-2275 4225);
FORCEPROP 1 LAST COMMENT_BODY TRUE
J 0
(-2550 4075);
DISPLAY 0.872340 (-2550 4075);
PAINT GREEN (-2550 4075);
DISPLAY INVISIBLE (-2550 4075);
FORCEPROP 1 LAST OFFPAGE TRUE
J 0
(-2175 4050);
DISPLAY 0.872340 (-2175 4050);
PAINT GREEN (-2175 4050);
DISPLAY INVISIBLE (-2175 4050);
FORCEPROP 2 LAST CDS_LIB mstr_standard
J 0
(-2500 4175);
DISPLAY 0.723404 (-2500 4175);
PAINT MONO (-2500 4175);
DISPLAY INVISIBLE (-2500 4175);
FORCEADD TAP..1
(-3225 5900);
FORCEPROP 3 LASTPIN (-3275 5900) SIG_NAME M_I_CPU1_SA_DQ<1>
J 0
(-3265 5910);
DISPLAY 0.659574 (-3265 5910);
PAINT MONO (-3265 5910);
DISPLAY INVISIBLE (-3265 5910);
FORCEPROP 1 LASTPIN (-3275 5900) BN 1
J 0
(-3287 5908);
DISPLAY 0.489362 (-3287 5908);
PAINT GREEN (-3287 5908);
FORCEPROP 2 LAST CDS_LIB mstr_standard
J 0
(-3225 5900);
DISPLAY 0.723404 (-3225 5900);
PAINT MONO (-3225 5900);
DISPLAY INVISIBLE (-3225 5900);
FORCEPROP 1 LAST BODY_TYPE PLUMBING
J 0
(-3225 5950);
DISPLAY 0.872340 (-3225 5950);
PAINT GREEN (-3225 5950);
DISPLAY INVISIBLE (-3225 5950);
FORCEPROP 1 LAST HDL_TAP TRUE
J 0
(-2900 5775);
DISPLAY 0.872340 (-2900 5775);
DISPLAY INVISIBLE (-2900 5775);
FORCEPROP 1 LAST PATH I162
J 0
(-3227 5900);
DISPLAY 0.872340 (-3227 5900);
PAINT GREEN (-3227 5900);
DISPLAY INVISIBLE (-3227 5900);
FORCEADD TAP..1
(-3225 5950);
FORCEPROP 3 LASTPIN (-3275 5950) SIG_NAME M_I_CPU1_SA_DQ<0>
J 0
(-3265 5960);
DISPLAY 0.659574 (-3265 5960);
PAINT MONO (-3265 5960);
DISPLAY INVISIBLE (-3265 5960);
FORCEPROP 1 LASTPIN (-3275 5950) BN 0
J 0
(-3287 5958);
DISPLAY 0.489362 (-3287 5958);
PAINT GREEN (-3287 5958);
FORCEPROP 2 LAST CDS_LIB mstr_standard
J 0
(-3225 5950);
DISPLAY 0.723404 (-3225 5950);
PAINT MONO (-3225 5950);
DISPLAY INVISIBLE (-3225 5950);
FORCEPROP 1 LAST BODY_TYPE PLUMBING
J 0
(-3225 6000);
DISPLAY 0.872340 (-3225 6000);
PAINT GREEN (-3225 6000);
DISPLAY INVISIBLE (-3225 6000);
FORCEPROP 1 LAST HDL_TAP TRUE
J 0
(-2900 5825);
DISPLAY 0.872340 (-2900 5825);
DISPLAY INVISIBLE (-2900 5825);
FORCEPROP 1 LAST PATH I163
J 0
(-3227 5950);
DISPLAY 0.872340 (-3227 5950);
PAINT GREEN (-3227 5950);
DISPLAY INVISIBLE (-3227 5950);
FORCEADD TAP..1
(-3225 5800);
FORCEPROP 3 LASTPIN (-3275 5800) SIG_NAME M_I_CPU1_SA_DQ<3>
J 0
(-3265 5810);
DISPLAY 0.659574 (-3265 5810);
PAINT MONO (-3265 5810);
DISPLAY INVISIBLE (-3265 5810);
FORCEPROP 1 LASTPIN (-3275 5800) BN 3
J 0
(-3287 5808);
DISPLAY 0.489362 (-3287 5808);
PAINT GREEN (-3287 5808);
FORCEPROP 2 LAST CDS_LIB mstr_standard
J 0
(-3225 5800);
DISPLAY 0.723404 (-3225 5800);
PAINT MONO (-3225 5800);
DISPLAY INVISIBLE (-3225 5800);
FORCEPROP 1 LAST BODY_TYPE PLUMBING
J 0
(-3225 5850);
DISPLAY 0.872340 (-3225 5850);
PAINT GREEN (-3225 5850);
DISPLAY INVISIBLE (-3225 5850);
FORCEPROP 1 LAST HDL_TAP TRUE
J 0
(-2900 5675);
DISPLAY 0.872340 (-2900 5675);
DISPLAY INVISIBLE (-2900 5675);
FORCEPROP 1 LAST PATH I164
J 0
(-3227 5800);
DISPLAY 0.872340 (-3227 5800);
PAINT GREEN (-3227 5800);
DISPLAY INVISIBLE (-3227 5800);
FORCEADD TAP..1
(-3225 5850);
FORCEPROP 3 LASTPIN (-3275 5850) SIG_NAME M_I_CPU1_SA_DQ<2>
J 0
(-3265 5860);
DISPLAY 0.659574 (-3265 5860);
PAINT MONO (-3265 5860);
DISPLAY INVISIBLE (-3265 5860);
FORCEPROP 1 LASTPIN (-3275 5850) BN 2
J 0
(-3287 5858);
DISPLAY 0.489362 (-3287 5858);
PAINT GREEN (-3287 5858);
FORCEPROP 2 LAST CDS_LIB mstr_standard
J 0
(-3225 5850);
DISPLAY 0.723404 (-3225 5850);
PAINT MONO (-3225 5850);
DISPLAY INVISIBLE (-3225 5850);
FORCEPROP 1 LAST BODY_TYPE PLUMBING
J 0
(-3225 5900);
DISPLAY 0.872340 (-3225 5900);
PAINT GREEN (-3225 5900);
DISPLAY INVISIBLE (-3225 5900);
FORCEPROP 1 LAST HDL_TAP TRUE
J 0
(-2900 5725);
DISPLAY 0.872340 (-2900 5725);
DISPLAY INVISIBLE (-2900 5725);
FORCEPROP 1 LAST PATH I165
J 0
(-3227 5850);
DISPLAY 0.872340 (-3227 5850);
PAINT GREEN (-3227 5850);
DISPLAY INVISIBLE (-3227 5850);
FORCEADD TAP..1
(-3225 5750);
FORCEPROP 3 LASTPIN (-3275 5750) SIG_NAME M_I_CPU1_SA_DQ<4>
J 0
(-3265 5760);
DISPLAY 0.659574 (-3265 5760);
PAINT MONO (-3265 5760);
DISPLAY INVISIBLE (-3265 5760);
FORCEPROP 1 LASTPIN (-3275 5750) BN 4
J 0
(-3287 5758);
DISPLAY 0.489362 (-3287 5758);
PAINT GREEN (-3287 5758);
FORCEPROP 2 LAST CDS_LIB mstr_standard
J 0
(-3225 5750);
DISPLAY 0.723404 (-3225 5750);
PAINT MONO (-3225 5750);
DISPLAY INVISIBLE (-3225 5750);
FORCEPROP 1 LAST BODY_TYPE PLUMBING
J 0
(-3225 5800);
DISPLAY 0.872340 (-3225 5800);
PAINT GREEN (-3225 5800);
DISPLAY INVISIBLE (-3225 5800);
FORCEPROP 1 LAST HDL_TAP TRUE
J 0
(-2900 5625);
DISPLAY 0.872340 (-2900 5625);
DISPLAY INVISIBLE (-2900 5625);
FORCEPROP 1 LAST PATH I166
J 0
(-3227 5750);
DISPLAY 0.872340 (-3227 5750);
PAINT GREEN (-3227 5750);
DISPLAY INVISIBLE (-3227 5750);
FORCEADD TAP..1
(-3225 5650);
FORCEPROP 3 LASTPIN (-3275 5650) SIG_NAME M_I_CPU1_SA_DQ<6>
J 0
(-3265 5660);
DISPLAY 0.659574 (-3265 5660);
PAINT MONO (-3265 5660);
DISPLAY INVISIBLE (-3265 5660);
FORCEPROP 1 LASTPIN (-3275 5650) BN 6
J 0
(-3287 5658);
DISPLAY 0.489362 (-3287 5658);
PAINT GREEN (-3287 5658);
FORCEPROP 2 LAST CDS_LIB mstr_standard
J 0
(-3225 5650);
DISPLAY 0.723404 (-3225 5650);
PAINT MONO (-3225 5650);
DISPLAY INVISIBLE (-3225 5650);
FORCEPROP 1 LAST BODY_TYPE PLUMBING
J 0
(-3225 5700);
DISPLAY 0.872340 (-3225 5700);
PAINT GREEN (-3225 5700);
DISPLAY INVISIBLE (-3225 5700);
FORCEPROP 1 LAST HDL_TAP TRUE
J 0
(-2900 5525);
DISPLAY 0.872340 (-2900 5525);
DISPLAY INVISIBLE (-2900 5525);
FORCEPROP 1 LAST PATH I167
J 0
(-3227 5650);
DISPLAY 0.872340 (-3227 5650);
PAINT GREEN (-3227 5650);
DISPLAY INVISIBLE (-3227 5650);
FORCEADD TAP..1
(-3225 5700);
FORCEPROP 3 LASTPIN (-3275 5700) SIG_NAME M_I_CPU1_SA_DQ<5>
J 0
(-3265 5710);
DISPLAY 0.659574 (-3265 5710);
PAINT MONO (-3265 5710);
DISPLAY INVISIBLE (-3265 5710);
FORCEPROP 1 LASTPIN (-3275 5700) BN 5
J 0
(-3287 5708);
DISPLAY 0.489362 (-3287 5708);
PAINT GREEN (-3287 5708);
FORCEPROP 2 LAST CDS_LIB mstr_standard
J 0
(-3225 5700);
DISPLAY 0.723404 (-3225 5700);
PAINT MONO (-3225 5700);
DISPLAY INVISIBLE (-3225 5700);
FORCEPROP 1 LAST BODY_TYPE PLUMBING
J 0
(-3225 5750);
DISPLAY 0.872340 (-3225 5750);
PAINT GREEN (-3225 5750);
DISPLAY INVISIBLE (-3225 5750);
FORCEPROP 1 LAST HDL_TAP TRUE
J 0
(-2900 5575);
DISPLAY 0.872340 (-2900 5575);
DISPLAY INVISIBLE (-2900 5575);
FORCEPROP 1 LAST PATH I168
J 0
(-3227 5700);
DISPLAY 0.872340 (-3227 5700);
PAINT GREEN (-3227 5700);
DISPLAY INVISIBLE (-3227 5700);
FORCEADD TAP..1
(-3225 5500);
FORCEPROP 3 LASTPIN (-3275 5500) SIG_NAME M_I_CPU1_SA_DQ<8>
J 0
(-3265 5510);
DISPLAY 0.659574 (-3265 5510);
PAINT MONO (-3265 5510);
DISPLAY INVISIBLE (-3265 5510);
FORCEPROP 1 LASTPIN (-3275 5500) BN 8
J 0
(-3287 5508);
DISPLAY 0.489362 (-3287 5508);
PAINT GREEN (-3287 5508);
FORCEPROP 2 LAST CDS_LIB mstr_standard
J 0
(-3225 5500);
DISPLAY 0.723404 (-3225 5500);
PAINT MONO (-3225 5500);
DISPLAY INVISIBLE (-3225 5500);
FORCEPROP 1 LAST BODY_TYPE PLUMBING
J 0
(-3225 5550);
DISPLAY 0.872340 (-3225 5550);
PAINT GREEN (-3225 5550);
DISPLAY INVISIBLE (-3225 5550);
FORCEPROP 1 LAST HDL_TAP TRUE
J 0
(-2900 5375);
DISPLAY 0.872340 (-2900 5375);
DISPLAY INVISIBLE (-2900 5375);
FORCEPROP 1 LAST PATH I169
J 0
(-3227 5500);
DISPLAY 0.872340 (-3227 5500);
PAINT GREEN (-3227 5500);
DISPLAY INVISIBLE (-3227 5500);
FORCEADD TAP..1
(-3225 5600);
FORCEPROP 3 LASTPIN (-3275 5600) SIG_NAME M_I_CPU1_SA_DQ<7>
J 0
(-3265 5610);
DISPLAY 0.659574 (-3265 5610);
PAINT MONO (-3265 5610);
DISPLAY INVISIBLE (-3265 5610);
FORCEPROP 1 LASTPIN (-3275 5600) BN 7
J 0
(-3287 5608);
DISPLAY 0.489362 (-3287 5608);
PAINT GREEN (-3287 5608);
FORCEPROP 2 LAST CDS_LIB mstr_standard
J 0
(-3225 5600);
DISPLAY 0.723404 (-3225 5600);
PAINT MONO (-3225 5600);
DISPLAY INVISIBLE (-3225 5600);
FORCEPROP 1 LAST BODY_TYPE PLUMBING
J 0
(-3225 5650);
DISPLAY 0.872340 (-3225 5650);
PAINT GREEN (-3225 5650);
DISPLAY INVISIBLE (-3225 5650);
FORCEPROP 1 LAST HDL_TAP TRUE
J 0
(-2900 5475);
DISPLAY 0.872340 (-2900 5475);
DISPLAY INVISIBLE (-2900 5475);
FORCEPROP 1 LAST PATH I170
J 0
(-3227 5600);
DISPLAY 0.872340 (-3227 5600);
PAINT GREEN (-3227 5600);
DISPLAY INVISIBLE (-3227 5600);
FORCEADD TAP..1
(-3225 5400);
FORCEPROP 3 LASTPIN (-3275 5400) SIG_NAME M_I_CPU1_SA_DQ<10>
J 0
(-3265 5410);
DISPLAY 0.659574 (-3265 5410);
PAINT MONO (-3265 5410);
DISPLAY INVISIBLE (-3265 5410);
FORCEPROP 1 LASTPIN (-3275 5400) BN 10
J 0
(-3287 5408);
DISPLAY 0.489362 (-3287 5408);
PAINT GREEN (-3287 5408);
FORCEPROP 2 LAST CDS_LIB mstr_standard
J 0
(-3225 5400);
DISPLAY 0.723404 (-3225 5400);
PAINT MONO (-3225 5400);
DISPLAY INVISIBLE (-3225 5400);
FORCEPROP 1 LAST BODY_TYPE PLUMBING
J 0
(-3225 5450);
DISPLAY 0.872340 (-3225 5450);
PAINT GREEN (-3225 5450);
DISPLAY INVISIBLE (-3225 5450);
FORCEPROP 1 LAST HDL_TAP TRUE
J 0
(-2900 5275);
DISPLAY 0.872340 (-2900 5275);
DISPLAY INVISIBLE (-2900 5275);
FORCEPROP 1 LAST PATH I171
J 0
(-3227 5400);
DISPLAY 0.872340 (-3227 5400);
PAINT GREEN (-3227 5400);
DISPLAY INVISIBLE (-3227 5400);
FORCEADD TAP..1
(-3225 5450);
FORCEPROP 3 LASTPIN (-3275 5450) SIG_NAME M_I_CPU1_SA_DQ<9>
J 0
(-3265 5460);
DISPLAY 0.659574 (-3265 5460);
PAINT MONO (-3265 5460);
DISPLAY INVISIBLE (-3265 5460);
FORCEPROP 1 LASTPIN (-3275 5450) BN 9
J 0
(-3287 5458);
DISPLAY 0.489362 (-3287 5458);
PAINT GREEN (-3287 5458);
FORCEPROP 2 LAST CDS_LIB mstr_standard
J 0
(-3225 5450);
DISPLAY 0.723404 (-3225 5450);
PAINT MONO (-3225 5450);
DISPLAY INVISIBLE (-3225 5450);
FORCEPROP 1 LAST BODY_TYPE PLUMBING
J 0
(-3225 5500);
DISPLAY 0.872340 (-3225 5500);
PAINT GREEN (-3225 5500);
DISPLAY INVISIBLE (-3225 5500);
FORCEPROP 1 LAST HDL_TAP TRUE
J 0
(-2900 5325);
DISPLAY 0.872340 (-2900 5325);
DISPLAY INVISIBLE (-2900 5325);
FORCEPROP 1 LAST PATH I172
J 0
(-3227 5450);
DISPLAY 0.872340 (-3227 5450);
PAINT GREEN (-3227 5450);
DISPLAY INVISIBLE (-3227 5450);
FORCEADD TAP..1
(-3225 5250);
FORCEPROP 3 LASTPIN (-3275 5250) SIG_NAME M_I_CPU1_SA_DQ<13>
J 0
(-3265 5260);
DISPLAY 0.659574 (-3265 5260);
PAINT MONO (-3265 5260);
DISPLAY INVISIBLE (-3265 5260);
FORCEPROP 1 LASTPIN (-3275 5250) BN 13
J 0
(-3287 5258);
DISPLAY 0.489362 (-3287 5258);
PAINT GREEN (-3287 5258);
FORCEPROP 2 LAST CDS_LIB mstr_standard
J 0
(-3225 5250);
DISPLAY 0.723404 (-3225 5250);
PAINT MONO (-3225 5250);
DISPLAY INVISIBLE (-3225 5250);
FORCEPROP 1 LAST BODY_TYPE PLUMBING
J 0
(-3225 5300);
DISPLAY 0.872340 (-3225 5300);
PAINT GREEN (-3225 5300);
DISPLAY INVISIBLE (-3225 5300);
FORCEPROP 1 LAST HDL_TAP TRUE
J 0
(-2900 5125);
DISPLAY 0.872340 (-2900 5125);
DISPLAY INVISIBLE (-2900 5125);
FORCEPROP 1 LAST PATH I173
J 0
(-3227 5250);
DISPLAY 0.872340 (-3227 5250);
PAINT GREEN (-3227 5250);
DISPLAY INVISIBLE (-3227 5250);
FORCEADD TAP..1
(-3225 5300);
FORCEPROP 3 LASTPIN (-3275 5300) SIG_NAME M_I_CPU1_SA_DQ<12>
J 0
(-3265 5310);
DISPLAY 0.659574 (-3265 5310);
PAINT MONO (-3265 5310);
DISPLAY INVISIBLE (-3265 5310);
FORCEPROP 1 LASTPIN (-3275 5300) BN 12
J 0
(-3287 5308);
DISPLAY 0.489362 (-3287 5308);
PAINT GREEN (-3287 5308);
FORCEPROP 2 LAST CDS_LIB mstr_standard
J 0
(-3225 5300);
DISPLAY 0.723404 (-3225 5300);
PAINT MONO (-3225 5300);
DISPLAY INVISIBLE (-3225 5300);
FORCEPROP 1 LAST BODY_TYPE PLUMBING
J 0
(-3225 5350);
DISPLAY 0.872340 (-3225 5350);
PAINT GREEN (-3225 5350);
DISPLAY INVISIBLE (-3225 5350);
FORCEPROP 1 LAST HDL_TAP TRUE
J 0
(-2900 5175);
DISPLAY 0.872340 (-2900 5175);
DISPLAY INVISIBLE (-2900 5175);
FORCEPROP 1 LAST PATH I174
J 0
(-3227 5300);
DISPLAY 0.872340 (-3227 5300);
PAINT GREEN (-3227 5300);
DISPLAY INVISIBLE (-3227 5300);
FORCEADD TAP..1
(-3225 5350);
FORCEPROP 3 LASTPIN (-3275 5350) SIG_NAME M_I_CPU1_SA_DQ<11>
J 0
(-3265 5360);
DISPLAY 0.659574 (-3265 5360);
PAINT MONO (-3265 5360);
DISPLAY INVISIBLE (-3265 5360);
FORCEPROP 1 LASTPIN (-3275 5350) BN 11
J 0
(-3287 5358);
DISPLAY 0.489362 (-3287 5358);
PAINT GREEN (-3287 5358);
FORCEPROP 2 LAST CDS_LIB mstr_standard
J 0
(-3225 5350);
DISPLAY 0.723404 (-3225 5350);
PAINT MONO (-3225 5350);
DISPLAY INVISIBLE (-3225 5350);
FORCEPROP 1 LAST BODY_TYPE PLUMBING
J 0
(-3225 5400);
DISPLAY 0.872340 (-3225 5400);
PAINT GREEN (-3225 5400);
DISPLAY INVISIBLE (-3225 5400);
FORCEPROP 1 LAST HDL_TAP TRUE
J 0
(-2900 5225);
DISPLAY 0.872340 (-2900 5225);
DISPLAY INVISIBLE (-2900 5225);
FORCEPROP 1 LAST PATH I175
J 0
(-3227 5350);
DISPLAY 0.872340 (-3227 5350);
PAINT GREEN (-3227 5350);
DISPLAY INVISIBLE (-3227 5350);
FORCEADD TAP..1
(-3225 5200);
FORCEPROP 3 LASTPIN (-3275 5200) SIG_NAME M_I_CPU1_SA_DQ<14>
J 0
(-3265 5210);
DISPLAY 0.659574 (-3265 5210);
PAINT MONO (-3265 5210);
DISPLAY INVISIBLE (-3265 5210);
FORCEPROP 1 LASTPIN (-3275 5200) BN 14
J 0
(-3287 5208);
DISPLAY 0.489362 (-3287 5208);
PAINT GREEN (-3287 5208);
FORCEPROP 2 LAST CDS_LIB mstr_standard
J 0
(-3225 5200);
DISPLAY 0.723404 (-3225 5200);
PAINT MONO (-3225 5200);
DISPLAY INVISIBLE (-3225 5200);
FORCEPROP 1 LAST BODY_TYPE PLUMBING
J 0
(-3225 5250);
DISPLAY 0.872340 (-3225 5250);
PAINT GREEN (-3225 5250);
DISPLAY INVISIBLE (-3225 5250);
FORCEPROP 1 LAST HDL_TAP TRUE
J 0
(-2900 5075);
DISPLAY 0.872340 (-2900 5075);
DISPLAY INVISIBLE (-2900 5075);
FORCEPROP 1 LAST PATH I176
J 0
(-3227 5200);
DISPLAY 0.872340 (-3227 5200);
PAINT GREEN (-3227 5200);
DISPLAY INVISIBLE (-3227 5200);
FORCEADD TAP..1
(-3225 5150);
FORCEPROP 3 LASTPIN (-3275 5150) SIG_NAME M_I_CPU1_SA_DQ<15>
J 0
(-3265 5160);
DISPLAY 0.659574 (-3265 5160);
PAINT MONO (-3265 5160);
DISPLAY INVISIBLE (-3265 5160);
FORCEPROP 1 LASTPIN (-3275 5150) BN 15
J 0
(-3287 5158);
DISPLAY 0.489362 (-3287 5158);
PAINT GREEN (-3287 5158);
FORCEPROP 2 LAST CDS_LIB mstr_standard
J 0
(-3225 5150);
DISPLAY 0.723404 (-3225 5150);
PAINT MONO (-3225 5150);
DISPLAY INVISIBLE (-3225 5150);
FORCEPROP 1 LAST BODY_TYPE PLUMBING
J 0
(-3225 5200);
DISPLAY 0.872340 (-3225 5200);
PAINT GREEN (-3225 5200);
DISPLAY INVISIBLE (-3225 5200);
FORCEPROP 1 LAST HDL_TAP TRUE
J 0
(-2900 5025);
DISPLAY 0.872340 (-2900 5025);
DISPLAY INVISIBLE (-2900 5025);
FORCEPROP 1 LAST PATH I177
J 0
(-3227 5150);
DISPLAY 0.872340 (-3227 5150);
PAINT GREEN (-3227 5150);
DISPLAY INVISIBLE (-3227 5150);
FORCEADD TAP..1
(-3225 5050);
FORCEPROP 3 LASTPIN (-3275 5050) SIG_NAME M_I_CPU1_SA_DQ<16>
J 0
(-3265 5060);
DISPLAY 0.659574 (-3265 5060);
PAINT MONO (-3265 5060);
DISPLAY INVISIBLE (-3265 5060);
FORCEPROP 1 LASTPIN (-3275 5050) BN 16
J 0
(-3287 5058);
DISPLAY 0.489362 (-3287 5058);
PAINT GREEN (-3287 5058);
FORCEPROP 2 LAST CDS_LIB mstr_standard
J 0
(-3225 5050);
DISPLAY 0.723404 (-3225 5050);
PAINT MONO (-3225 5050);
DISPLAY INVISIBLE (-3225 5050);
FORCEPROP 1 LAST BODY_TYPE PLUMBING
J 0
(-3225 5100);
DISPLAY 0.872340 (-3225 5100);
PAINT GREEN (-3225 5100);
DISPLAY INVISIBLE (-3225 5100);
FORCEPROP 1 LAST HDL_TAP TRUE
J 0
(-2900 4925);
DISPLAY 0.872340 (-2900 4925);
DISPLAY INVISIBLE (-2900 4925);
FORCEPROP 1 LAST PATH I178
J 0
(-3227 5050);
DISPLAY 0.872340 (-3227 5050);
PAINT GREEN (-3227 5050);
DISPLAY INVISIBLE (-3227 5050);
FORCEADD TAP..1
(-3225 5000);
FORCEPROP 3 LASTPIN (-3275 5000) SIG_NAME M_I_CPU1_SA_DQ<17>
J 0
(-3265 5010);
DISPLAY 0.659574 (-3265 5010);
PAINT MONO (-3265 5010);
DISPLAY INVISIBLE (-3265 5010);
FORCEPROP 1 LASTPIN (-3275 5000) BN 17
J 0
(-3287 5008);
DISPLAY 0.489362 (-3287 5008);
PAINT GREEN (-3287 5008);
FORCEPROP 2 LAST CDS_LIB mstr_standard
J 0
(-3225 5000);
DISPLAY 0.723404 (-3225 5000);
PAINT MONO (-3225 5000);
DISPLAY INVISIBLE (-3225 5000);
FORCEPROP 1 LAST BODY_TYPE PLUMBING
J 0
(-3225 5050);
DISPLAY 0.872340 (-3225 5050);
PAINT GREEN (-3225 5050);
DISPLAY INVISIBLE (-3225 5050);
FORCEPROP 1 LAST HDL_TAP TRUE
J 0
(-2900 4875);
DISPLAY 0.872340 (-2900 4875);
DISPLAY INVISIBLE (-2900 4875);
FORCEPROP 1 LAST PATH I179
J 0
(-3227 5000);
DISPLAY 0.872340 (-3227 5000);
PAINT GREEN (-3227 5000);
DISPLAY INVISIBLE (-3227 5000);
FORCEADD TAP..1
(-3225 4900);
FORCEPROP 3 LASTPIN (-3275 4900) SIG_NAME M_I_CPU1_SA_DQ<19>
J 0
(-3265 4910);
DISPLAY 0.659574 (-3265 4910);
PAINT MONO (-3265 4910);
DISPLAY INVISIBLE (-3265 4910);
FORCEPROP 1 LASTPIN (-3275 4900) BN 19
J 0
(-3287 4908);
DISPLAY 0.489362 (-3287 4908);
PAINT GREEN (-3287 4908);
FORCEPROP 2 LAST CDS_LIB mstr_standard
J 0
(-3225 4900);
DISPLAY 0.723404 (-3225 4900);
PAINT MONO (-3225 4900);
DISPLAY INVISIBLE (-3225 4900);
FORCEPROP 1 LAST BODY_TYPE PLUMBING
J 0
(-3225 4950);
DISPLAY 0.872340 (-3225 4950);
PAINT GREEN (-3225 4950);
DISPLAY INVISIBLE (-3225 4950);
FORCEPROP 1 LAST HDL_TAP TRUE
J 0
(-2900 4775);
DISPLAY 0.872340 (-2900 4775);
DISPLAY INVISIBLE (-2900 4775);
FORCEPROP 1 LAST PATH I180
J 0
(-3227 4900);
DISPLAY 0.872340 (-3227 4900);
PAINT GREEN (-3227 4900);
DISPLAY INVISIBLE (-3227 4900);
FORCEADD TAP..1
(-3225 4950);
FORCEPROP 3 LASTPIN (-3275 4950) SIG_NAME M_I_CPU1_SA_DQ<18>
J 0
(-3265 4960);
DISPLAY 0.659574 (-3265 4960);
PAINT MONO (-3265 4960);
DISPLAY INVISIBLE (-3265 4960);
FORCEPROP 1 LASTPIN (-3275 4950) BN 18
J 0
(-3287 4958);
DISPLAY 0.489362 (-3287 4958);
PAINT GREEN (-3287 4958);
FORCEPROP 2 LAST CDS_LIB mstr_standard
J 0
(-3225 4950);
DISPLAY 0.723404 (-3225 4950);
PAINT MONO (-3225 4950);
DISPLAY INVISIBLE (-3225 4950);
FORCEPROP 1 LAST BODY_TYPE PLUMBING
J 0
(-3225 5000);
DISPLAY 0.872340 (-3225 5000);
PAINT GREEN (-3225 5000);
DISPLAY INVISIBLE (-3225 5000);
FORCEPROP 1 LAST HDL_TAP TRUE
J 0
(-2900 4825);
DISPLAY 0.872340 (-2900 4825);
DISPLAY INVISIBLE (-2900 4825);
FORCEPROP 1 LAST PATH I181
J 0
(-3227 4950);
DISPLAY 0.872340 (-3227 4950);
PAINT GREEN (-3227 4950);
DISPLAY INVISIBLE (-3227 4950);
FORCEADD TAP..1
(-3225 4850);
FORCEPROP 3 LASTPIN (-3275 4850) SIG_NAME M_I_CPU1_SA_DQ<20>
J 0
(-3265 4860);
DISPLAY 0.659574 (-3265 4860);
PAINT MONO (-3265 4860);
DISPLAY INVISIBLE (-3265 4860);
FORCEPROP 1 LASTPIN (-3275 4850) BN 20
J 0
(-3287 4858);
DISPLAY 0.489362 (-3287 4858);
PAINT GREEN (-3287 4858);
FORCEPROP 2 LAST CDS_LIB mstr_standard
J 0
(-3225 4850);
DISPLAY 0.723404 (-3225 4850);
PAINT MONO (-3225 4850);
DISPLAY INVISIBLE (-3225 4850);
FORCEPROP 1 LAST BODY_TYPE PLUMBING
J 0
(-3225 4900);
DISPLAY 0.872340 (-3225 4900);
PAINT GREEN (-3225 4900);
DISPLAY INVISIBLE (-3225 4900);
FORCEPROP 1 LAST HDL_TAP TRUE
J 0
(-2900 4725);
DISPLAY 0.872340 (-2900 4725);
DISPLAY INVISIBLE (-2900 4725);
FORCEPROP 1 LAST PATH I182
J 0
(-3227 4850);
DISPLAY 0.872340 (-3227 4850);
PAINT GREEN (-3227 4850);
DISPLAY INVISIBLE (-3227 4850);
FORCEADD TAP..1
(-3225 4750);
FORCEPROP 3 LASTPIN (-3275 4750) SIG_NAME M_I_CPU1_SA_DQ<22>
J 0
(-3265 4760);
DISPLAY 0.659574 (-3265 4760);
PAINT MONO (-3265 4760);
DISPLAY INVISIBLE (-3265 4760);
FORCEPROP 1 LASTPIN (-3275 4750) BN 22
J 0
(-3287 4758);
DISPLAY 0.489362 (-3287 4758);
PAINT GREEN (-3287 4758);
FORCEPROP 2 LAST CDS_LIB mstr_standard
J 0
(-3225 4750);
DISPLAY 0.723404 (-3225 4750);
PAINT MONO (-3225 4750);
DISPLAY INVISIBLE (-3225 4750);
FORCEPROP 1 LAST BODY_TYPE PLUMBING
J 0
(-3225 4800);
DISPLAY 0.872340 (-3225 4800);
PAINT GREEN (-3225 4800);
DISPLAY INVISIBLE (-3225 4800);
FORCEPROP 1 LAST HDL_TAP TRUE
J 0
(-2900 4625);
DISPLAY 0.872340 (-2900 4625);
DISPLAY INVISIBLE (-2900 4625);
FORCEPROP 1 LAST PATH I183
J 0
(-3227 4750);
DISPLAY 0.872340 (-3227 4750);
PAINT GREEN (-3227 4750);
DISPLAY INVISIBLE (-3227 4750);
FORCEADD TAP..1
(-3225 4800);
FORCEPROP 3 LASTPIN (-3275 4800) SIG_NAME M_I_CPU1_SA_DQ<21>
J 0
(-3265 4810);
DISPLAY 0.659574 (-3265 4810);
PAINT MONO (-3265 4810);
DISPLAY INVISIBLE (-3265 4810);
FORCEPROP 1 LASTPIN (-3275 4800) BN 21
J 0
(-3287 4808);
DISPLAY 0.489362 (-3287 4808);
PAINT GREEN (-3287 4808);
FORCEPROP 2 LAST CDS_LIB mstr_standard
J 0
(-3225 4800);
DISPLAY 0.723404 (-3225 4800);
PAINT MONO (-3225 4800);
DISPLAY INVISIBLE (-3225 4800);
FORCEPROP 1 LAST BODY_TYPE PLUMBING
J 0
(-3225 4850);
DISPLAY 0.872340 (-3225 4850);
PAINT GREEN (-3225 4850);
DISPLAY INVISIBLE (-3225 4850);
FORCEPROP 1 LAST HDL_TAP TRUE
J 0
(-2900 4675);
DISPLAY 0.872340 (-2900 4675);
DISPLAY INVISIBLE (-2900 4675);
FORCEPROP 1 LAST PATH I184
J 0
(-3227 4800);
DISPLAY 0.872340 (-3227 4800);
PAINT GREEN (-3227 4800);
DISPLAY INVISIBLE (-3227 4800);
FORCEADD TAP..1
(-3225 4700);
FORCEPROP 3 LASTPIN (-3275 4700) SIG_NAME M_I_CPU1_SA_DQ<23>
J 0
(-3265 4710);
DISPLAY 0.659574 (-3265 4710);
PAINT MONO (-3265 4710);
DISPLAY INVISIBLE (-3265 4710);
FORCEPROP 1 LASTPIN (-3275 4700) BN 23
J 0
(-3287 4708);
DISPLAY 0.489362 (-3287 4708);
PAINT GREEN (-3287 4708);
FORCEPROP 2 LAST CDS_LIB mstr_standard
J 0
(-3225 4700);
DISPLAY 0.723404 (-3225 4700);
PAINT MONO (-3225 4700);
DISPLAY INVISIBLE (-3225 4700);
FORCEPROP 1 LAST BODY_TYPE PLUMBING
J 0
(-3225 4750);
DISPLAY 0.872340 (-3225 4750);
PAINT GREEN (-3225 4750);
DISPLAY INVISIBLE (-3225 4750);
FORCEPROP 1 LAST HDL_TAP TRUE
J 0
(-2900 4575);
DISPLAY 0.872340 (-2900 4575);
DISPLAY INVISIBLE (-2900 4575);
FORCEPROP 1 LAST PATH I185
J 0
(-3227 4700);
DISPLAY 0.872340 (-3227 4700);
PAINT GREEN (-3227 4700);
DISPLAY INVISIBLE (-3227 4700);
FORCEADD TAP..1
(-3225 4500);
FORCEPROP 3 LASTPIN (-3275 4500) SIG_NAME M_I_CPU1_SA_DQ<26>
J 0
(-3265 4510);
DISPLAY 0.659574 (-3265 4510);
PAINT MONO (-3265 4510);
DISPLAY INVISIBLE (-3265 4510);
FORCEPROP 1 LASTPIN (-3275 4500) BN 26
J 0
(-3287 4508);
DISPLAY 0.489362 (-3287 4508);
PAINT GREEN (-3287 4508);
FORCEPROP 2 LAST CDS_LIB mstr_standard
J 0
(-3225 4500);
DISPLAY 0.723404 (-3225 4500);
PAINT MONO (-3225 4500);
DISPLAY INVISIBLE (-3225 4500);
FORCEPROP 1 LAST BODY_TYPE PLUMBING
J 0
(-3225 4550);
DISPLAY 0.872340 (-3225 4550);
PAINT GREEN (-3225 4550);
DISPLAY INVISIBLE (-3225 4550);
FORCEPROP 1 LAST HDL_TAP TRUE
J 0
(-2900 4375);
DISPLAY 0.872340 (-2900 4375);
DISPLAY INVISIBLE (-2900 4375);
FORCEPROP 1 LAST PATH I186
J 0
(-3227 4500);
DISPLAY 0.872340 (-3227 4500);
PAINT GREEN (-3227 4500);
DISPLAY INVISIBLE (-3227 4500);
FORCEADD TAP..1
(-3225 4600);
FORCEPROP 3 LASTPIN (-3275 4600) SIG_NAME M_I_CPU1_SA_DQ<24>
J 0
(-3265 4610);
DISPLAY 0.659574 (-3265 4610);
PAINT MONO (-3265 4610);
DISPLAY INVISIBLE (-3265 4610);
FORCEPROP 1 LASTPIN (-3275 4600) BN 24
J 0
(-3287 4608);
DISPLAY 0.489362 (-3287 4608);
PAINT GREEN (-3287 4608);
FORCEPROP 2 LAST CDS_LIB mstr_standard
J 0
(-3225 4600);
DISPLAY 0.723404 (-3225 4600);
PAINT MONO (-3225 4600);
DISPLAY INVISIBLE (-3225 4600);
FORCEPROP 1 LAST BODY_TYPE PLUMBING
J 0
(-3225 4650);
DISPLAY 0.872340 (-3225 4650);
PAINT GREEN (-3225 4650);
DISPLAY INVISIBLE (-3225 4650);
FORCEPROP 1 LAST HDL_TAP TRUE
J 0
(-2900 4475);
DISPLAY 0.872340 (-2900 4475);
DISPLAY INVISIBLE (-2900 4475);
FORCEPROP 1 LAST PATH I187
J 0
(-3227 4600);
DISPLAY 0.872340 (-3227 4600);
PAINT GREEN (-3227 4600);
DISPLAY INVISIBLE (-3227 4600);
FORCEADD TAP..1
(-3225 4550);
FORCEPROP 3 LASTPIN (-3275 4550) SIG_NAME M_I_CPU1_SA_DQ<25>
J 0
(-3265 4560);
DISPLAY 0.659574 (-3265 4560);
PAINT MONO (-3265 4560);
DISPLAY INVISIBLE (-3265 4560);
FORCEPROP 1 LASTPIN (-3275 4550) BN 25
J 0
(-3287 4558);
DISPLAY 0.489362 (-3287 4558);
PAINT GREEN (-3287 4558);
FORCEPROP 2 LAST CDS_LIB mstr_standard
J 0
(-3225 4550);
DISPLAY 0.723404 (-3225 4550);
PAINT MONO (-3225 4550);
DISPLAY INVISIBLE (-3225 4550);
FORCEPROP 1 LAST BODY_TYPE PLUMBING
J 0
(-3225 4600);
DISPLAY 0.872340 (-3225 4600);
PAINT GREEN (-3225 4600);
DISPLAY INVISIBLE (-3225 4600);
FORCEPROP 1 LAST HDL_TAP TRUE
J 0
(-2900 4425);
DISPLAY 0.872340 (-2900 4425);
DISPLAY INVISIBLE (-2900 4425);
FORCEPROP 1 LAST PATH I188
J 0
(-3227 4550);
DISPLAY 0.872340 (-3227 4550);
PAINT GREEN (-3227 4550);
DISPLAY INVISIBLE (-3227 4550);
FORCEADD TAP..1
(-3225 4400);
FORCEPROP 3 LASTPIN (-3275 4400) SIG_NAME M_I_CPU1_SA_DQ<28>
J 0
(-3265 4410);
DISPLAY 0.659574 (-3265 4410);
PAINT MONO (-3265 4410);
DISPLAY INVISIBLE (-3265 4410);
FORCEPROP 1 LASTPIN (-3275 4400) BN 28
J 0
(-3287 4408);
DISPLAY 0.489362 (-3287 4408);
PAINT GREEN (-3287 4408);
FORCEPROP 2 LAST CDS_LIB mstr_standard
J 0
(-3225 4400);
DISPLAY 0.723404 (-3225 4400);
PAINT MONO (-3225 4400);
DISPLAY INVISIBLE (-3225 4400);
FORCEPROP 1 LAST BODY_TYPE PLUMBING
J 0
(-3225 4450);
DISPLAY 0.872340 (-3225 4450);
PAINT GREEN (-3225 4450);
DISPLAY INVISIBLE (-3225 4450);
FORCEPROP 1 LAST HDL_TAP TRUE
J 0
(-2900 4275);
DISPLAY 0.872340 (-2900 4275);
DISPLAY INVISIBLE (-2900 4275);
FORCEPROP 1 LAST PATH I189
J 0
(-3227 4400);
DISPLAY 0.872340 (-3227 4400);
PAINT GREEN (-3227 4400);
DISPLAY INVISIBLE (-3227 4400);
FORCEADD TAP..1
(-3225 4450);
FORCEPROP 3 LASTPIN (-3275 4450) SIG_NAME M_I_CPU1_SA_DQ<27>
J 0
(-3265 4460);
DISPLAY 0.659574 (-3265 4460);
PAINT MONO (-3265 4460);
DISPLAY INVISIBLE (-3265 4460);
FORCEPROP 1 LASTPIN (-3275 4450) BN 27
J 0
(-3287 4458);
DISPLAY 0.489362 (-3287 4458);
PAINT GREEN (-3287 4458);
FORCEPROP 2 LAST CDS_LIB mstr_standard
J 0
(-3225 4450);
DISPLAY 0.723404 (-3225 4450);
PAINT MONO (-3225 4450);
DISPLAY INVISIBLE (-3225 4450);
FORCEPROP 1 LAST BODY_TYPE PLUMBING
J 0
(-3225 4500);
DISPLAY 0.872340 (-3225 4500);
PAINT GREEN (-3225 4500);
DISPLAY INVISIBLE (-3225 4500);
FORCEPROP 1 LAST HDL_TAP TRUE
J 0
(-2900 4325);
DISPLAY 0.872340 (-2900 4325);
DISPLAY INVISIBLE (-2900 4325);
FORCEPROP 1 LAST PATH I190
J 0
(-3227 4450);
DISPLAY 0.872340 (-3227 4450);
PAINT GREEN (-3227 4450);
DISPLAY INVISIBLE (-3227 4450);
FORCEADD TAP..1
(-3225 4350);
FORCEPROP 3 LASTPIN (-3275 4350) SIG_NAME M_I_CPU1_SA_DQ<29>
J 0
(-3265 4360);
DISPLAY 0.659574 (-3265 4360);
PAINT MONO (-3265 4360);
DISPLAY INVISIBLE (-3265 4360);
FORCEPROP 1 LASTPIN (-3275 4350) BN 29
J 0
(-3287 4358);
DISPLAY 0.489362 (-3287 4358);
PAINT GREEN (-3287 4358);
FORCEPROP 2 LAST CDS_LIB mstr_standard
J 0
(-3225 4350);
DISPLAY 0.723404 (-3225 4350);
PAINT MONO (-3225 4350);
DISPLAY INVISIBLE (-3225 4350);
FORCEPROP 1 LAST BODY_TYPE PLUMBING
J 0
(-3225 4400);
DISPLAY 0.872340 (-3225 4400);
PAINT GREEN (-3225 4400);
DISPLAY INVISIBLE (-3225 4400);
FORCEPROP 1 LAST HDL_TAP TRUE
J 0
(-2900 4225);
DISPLAY 0.872340 (-2900 4225);
DISPLAY INVISIBLE (-2900 4225);
FORCEPROP 1 LAST PATH I191
J 0
(-3227 4350);
DISPLAY 0.872340 (-3227 4350);
PAINT GREEN (-3227 4350);
DISPLAY INVISIBLE (-3227 4350);
FORCEADD TAP..1
(-3225 4300);
FORCEPROP 3 LASTPIN (-3275 4300) SIG_NAME M_I_CPU1_SA_DQ<30>
J 0
(-3265 4310);
DISPLAY 0.659574 (-3265 4310);
PAINT MONO (-3265 4310);
DISPLAY INVISIBLE (-3265 4310);
FORCEPROP 1 LASTPIN (-3275 4300) BN 30
J 0
(-3287 4308);
DISPLAY 0.489362 (-3287 4308);
PAINT GREEN (-3287 4308);
FORCEPROP 2 LAST CDS_LIB mstr_standard
J 0
(-3225 4300);
DISPLAY 0.723404 (-3225 4300);
PAINT MONO (-3225 4300);
DISPLAY INVISIBLE (-3225 4300);
FORCEPROP 1 LAST BODY_TYPE PLUMBING
J 0
(-3225 4350);
DISPLAY 0.872340 (-3225 4350);
PAINT GREEN (-3225 4350);
DISPLAY INVISIBLE (-3225 4350);
FORCEPROP 1 LAST HDL_TAP TRUE
J 0
(-2900 4175);
DISPLAY 0.872340 (-2900 4175);
DISPLAY INVISIBLE (-2900 4175);
FORCEPROP 1 LAST PATH I192
J 0
(-3227 4300);
DISPLAY 0.872340 (-3227 4300);
PAINT GREEN (-3227 4300);
DISPLAY INVISIBLE (-3227 4300);
FORCEADD TAP..1
(-3225 4250);
FORCEPROP 3 LASTPIN (-3275 4250) SIG_NAME M_I_CPU1_SA_DQ<31>
J 0
(-3265 4260);
DISPLAY 0.659574 (-3265 4260);
PAINT MONO (-3265 4260);
DISPLAY INVISIBLE (-3265 4260);
FORCEPROP 1 LASTPIN (-3275 4250) BN 31
J 0
(-3287 4258);
DISPLAY 0.489362 (-3287 4258);
PAINT GREEN (-3287 4258);
FORCEPROP 2 LAST CDS_LIB mstr_standard
J 0
(-3225 4250);
DISPLAY 0.723404 (-3225 4250);
PAINT MONO (-3225 4250);
DISPLAY INVISIBLE (-3225 4250);
FORCEPROP 1 LAST BODY_TYPE PLUMBING
J 0
(-3225 4300);
DISPLAY 0.872340 (-3225 4300);
PAINT GREEN (-3225 4300);
DISPLAY INVISIBLE (-3225 4300);
FORCEPROP 1 LAST HDL_TAP TRUE
J 0
(-2900 4125);
DISPLAY 0.872340 (-2900 4125);
DISPLAY INVISIBLE (-2900 4125);
FORCEPROP 1 LAST PATH I193
J 0
(-3227 4250);
DISPLAY 0.872340 (-3227 4250);
PAINT GREEN (-3227 4250);
DISPLAY INVISIBLE (-3227 4250);
FORCEADD TAP..1
(-3225 4150);
FORCEPROP 3 LASTPIN (-3275 4150) SIG_NAME M_I_CPU1_SB_DQ<0>
J 0
(-3265 4160);
DISPLAY 0.659574 (-3265 4160);
PAINT MONO (-3265 4160);
DISPLAY INVISIBLE (-3265 4160);
FORCEPROP 1 LASTPIN (-3275 4150) BN 0
J 0
(-3287 4158);
DISPLAY 0.489362 (-3287 4158);
PAINT GREEN (-3287 4158);
FORCEPROP 2 LAST CDS_LIB mstr_standard
J 0
(-3225 4150);
DISPLAY 0.723404 (-3225 4150);
PAINT MONO (-3225 4150);
DISPLAY INVISIBLE (-3225 4150);
FORCEPROP 1 LAST BODY_TYPE PLUMBING
J 0
(-3225 4200);
DISPLAY 0.872340 (-3225 4200);
PAINT GREEN (-3225 4200);
DISPLAY INVISIBLE (-3225 4200);
FORCEPROP 1 LAST HDL_TAP TRUE
J 0
(-2900 4025);
DISPLAY 0.872340 (-2900 4025);
DISPLAY INVISIBLE (-2900 4025);
FORCEPROP 1 LAST PATH I194
J 0
(-3227 4150);
DISPLAY 0.872340 (-3227 4150);
PAINT GREEN (-3227 4150);
DISPLAY INVISIBLE (-3227 4150);
FORCEADD TAP..1
(-3225 4100);
FORCEPROP 3 LASTPIN (-3275 4100) SIG_NAME M_I_CPU1_SB_DQ<1>
J 0
(-3265 4110);
DISPLAY 0.659574 (-3265 4110);
PAINT MONO (-3265 4110);
DISPLAY INVISIBLE (-3265 4110);
FORCEPROP 1 LASTPIN (-3275 4100) BN 1
J 0
(-3287 4108);
DISPLAY 0.489362 (-3287 4108);
PAINT GREEN (-3287 4108);
FORCEPROP 2 LAST CDS_LIB mstr_standard
J 0
(-3225 4100);
DISPLAY 0.723404 (-3225 4100);
PAINT MONO (-3225 4100);
DISPLAY INVISIBLE (-3225 4100);
FORCEPROP 1 LAST BODY_TYPE PLUMBING
J 0
(-3225 4150);
DISPLAY 0.872340 (-3225 4150);
PAINT GREEN (-3225 4150);
DISPLAY INVISIBLE (-3225 4150);
FORCEPROP 1 LAST HDL_TAP TRUE
J 0
(-2900 3975);
DISPLAY 0.872340 (-2900 3975);
DISPLAY INVISIBLE (-2900 3975);
FORCEPROP 1 LAST PATH I195
J 0
(-3227 4100);
DISPLAY 0.872340 (-3227 4100);
PAINT GREEN (-3227 4100);
DISPLAY INVISIBLE (-3227 4100);
FORCEADD OFFPAGE..6
R 2
(-2625 2400);
FORCEPROP 2 LAST $XR0 105 
J 0
(-2411 2400);
DISPLAY 0.638298 (-2411 2400);
PAINT MONO (-2411 2400);
FORCEPROP 2 LAST PATH I196
J 0
(-2400 2450);
DISPLAY 1.021277 (-2400 2450);
DISPLAY INVISIBLE (-2400 2450);
FORCEPROP 1 LAST COMMENT_BODY TRUE
J 2
(-2725 2325);
DISPLAY 0.872340 (-2725 2325);
PAINT GREEN (-2725 2325);
DISPLAY INVISIBLE (-2725 2325);
FORCEPROP 1 LAST OFFPAGE TRUE
J 2
(-2950 2275);
DISPLAY 0.872340 (-2950 2275);
PAINT GREEN (-2950 2275);
DISPLAY INVISIBLE (-2950 2275);
FORCEPROP 2 LAST CDS_LIB mstr_standard
J 2
(-2625 2400);
DISPLAY 0.723404 (-2625 2400);
PAINT MONO (-2625 2400);
DISPLAY INVISIBLE (-2625 2400);
FORCEADD TAP..1
(-3225 4050);
FORCEPROP 3 LASTPIN (-3275 4050) SIG_NAME M_I_CPU1_SB_DQ<2>
J 0
(-3265 4060);
DISPLAY 0.659574 (-3265 4060);
PAINT MONO (-3265 4060);
DISPLAY INVISIBLE (-3265 4060);
FORCEPROP 1 LASTPIN (-3275 4050) BN 2
J 0
(-3287 4058);
DISPLAY 0.489362 (-3287 4058);
PAINT GREEN (-3287 4058);
FORCEPROP 2 LAST CDS_LIB mstr_standard
J 0
(-3225 4050);
DISPLAY 0.723404 (-3225 4050);
PAINT MONO (-3225 4050);
DISPLAY INVISIBLE (-3225 4050);
FORCEPROP 1 LAST BODY_TYPE PLUMBING
J 0
(-3225 4100);
DISPLAY 0.872340 (-3225 4100);
PAINT GREEN (-3225 4100);
DISPLAY INVISIBLE (-3225 4100);
FORCEPROP 1 LAST HDL_TAP TRUE
J 0
(-2900 3925);
DISPLAY 0.872340 (-2900 3925);
DISPLAY INVISIBLE (-2900 3925);
FORCEPROP 1 LAST PATH I197
J 0
(-3227 4050);
DISPLAY 0.872340 (-3227 4050);
PAINT GREEN (-3227 4050);
DISPLAY INVISIBLE (-3227 4050);
FORCEADD TAP..1
(-3225 4000);
FORCEPROP 3 LASTPIN (-3275 4000) SIG_NAME M_I_CPU1_SB_DQ<3>
J 0
(-3265 4010);
DISPLAY 0.659574 (-3265 4010);
PAINT MONO (-3265 4010);
DISPLAY INVISIBLE (-3265 4010);
FORCEPROP 1 LASTPIN (-3275 4000) BN 3
J 0
(-3287 4008);
DISPLAY 0.489362 (-3287 4008);
PAINT GREEN (-3287 4008);
FORCEPROP 2 LAST CDS_LIB mstr_standard
J 0
(-3225 4000);
DISPLAY 0.723404 (-3225 4000);
PAINT MONO (-3225 4000);
DISPLAY INVISIBLE (-3225 4000);
FORCEPROP 1 LAST BODY_TYPE PLUMBING
J 0
(-3225 4050);
DISPLAY 0.872340 (-3225 4050);
PAINT GREEN (-3225 4050);
DISPLAY INVISIBLE (-3225 4050);
FORCEPROP 1 LAST HDL_TAP TRUE
J 0
(-2900 3875);
DISPLAY 0.872340 (-2900 3875);
DISPLAY INVISIBLE (-2900 3875);
FORCEPROP 1 LAST PATH I198
J 0
(-3227 4000);
DISPLAY 0.872340 (-3227 4000);
PAINT GREEN (-3227 4000);
DISPLAY INVISIBLE (-3227 4000);
FORCEADD TAP..1
(-3225 3950);
FORCEPROP 3 LASTPIN (-3275 3950) SIG_NAME M_I_CPU1_SB_DQ<4>
J 0
(-3265 3960);
DISPLAY 0.659574 (-3265 3960);
PAINT MONO (-3265 3960);
DISPLAY INVISIBLE (-3265 3960);
FORCEPROP 1 LASTPIN (-3275 3950) BN 4
J 0
(-3287 3958);
DISPLAY 0.489362 (-3287 3958);
PAINT GREEN (-3287 3958);
FORCEPROP 2 LAST CDS_LIB mstr_standard
J 0
(-3225 3950);
DISPLAY 0.723404 (-3225 3950);
PAINT MONO (-3225 3950);
DISPLAY INVISIBLE (-3225 3950);
FORCEPROP 1 LAST BODY_TYPE PLUMBING
J 0
(-3225 4000);
DISPLAY 0.872340 (-3225 4000);
PAINT GREEN (-3225 4000);
DISPLAY INVISIBLE (-3225 4000);
FORCEPROP 1 LAST HDL_TAP TRUE
J 0
(-2900 3825);
DISPLAY 0.872340 (-2900 3825);
DISPLAY INVISIBLE (-2900 3825);
FORCEPROP 1 LAST PATH I199
J 0
(-3227 3950);
DISPLAY 0.872340 (-3227 3950);
PAINT GREEN (-3227 3950);
DISPLAY INVISIBLE (-3227 3950);
FORCEADD TAP..1
(-3225 3900);
FORCEPROP 3 LASTPIN (-3275 3900) SIG_NAME M_I_CPU1_SB_DQ<5>
J 0
(-3265 3910);
DISPLAY 0.659574 (-3265 3910);
PAINT MONO (-3265 3910);
DISPLAY INVISIBLE (-3265 3910);
FORCEPROP 1 LASTPIN (-3275 3900) BN 5
J 0
(-3287 3908);
DISPLAY 0.489362 (-3287 3908);
PAINT GREEN (-3287 3908);
FORCEPROP 2 LAST CDS_LIB mstr_standard
J 0
(-3225 3900);
DISPLAY 0.723404 (-3225 3900);
PAINT MONO (-3225 3900);
DISPLAY INVISIBLE (-3225 3900);
FORCEPROP 1 LAST BODY_TYPE PLUMBING
J 0
(-3225 3950);
DISPLAY 0.872340 (-3225 3950);
PAINT GREEN (-3225 3950);
DISPLAY INVISIBLE (-3225 3950);
FORCEPROP 1 LAST HDL_TAP TRUE
J 0
(-2900 3775);
DISPLAY 0.872340 (-2900 3775);
DISPLAY INVISIBLE (-2900 3775);
FORCEPROP 1 LAST PATH I200
J 0
(-3227 3900);
DISPLAY 0.872340 (-3227 3900);
PAINT GREEN (-3227 3900);
DISPLAY INVISIBLE (-3227 3900);
FORCEADD TAP..1
(-3225 3850);
FORCEPROP 3 LASTPIN (-3275 3850) SIG_NAME M_I_CPU1_SB_DQ<6>
J 0
(-3265 3860);
DISPLAY 0.659574 (-3265 3860);
PAINT MONO (-3265 3860);
DISPLAY INVISIBLE (-3265 3860);
FORCEPROP 1 LASTPIN (-3275 3850) BN 6
J 0
(-3287 3858);
DISPLAY 0.489362 (-3287 3858);
PAINT GREEN (-3287 3858);
FORCEPROP 2 LAST CDS_LIB mstr_standard
J 0
(-3225 3850);
DISPLAY 0.723404 (-3225 3850);
PAINT MONO (-3225 3850);
DISPLAY INVISIBLE (-3225 3850);
FORCEPROP 1 LAST BODY_TYPE PLUMBING
J 0
(-3225 3900);
DISPLAY 0.872340 (-3225 3900);
PAINT GREEN (-3225 3900);
DISPLAY INVISIBLE (-3225 3900);
FORCEPROP 1 LAST HDL_TAP TRUE
J 0
(-2900 3725);
DISPLAY 0.872340 (-2900 3725);
DISPLAY INVISIBLE (-2900 3725);
FORCEPROP 1 LAST PATH I201
J 0
(-3227 3850);
DISPLAY 0.872340 (-3227 3850);
PAINT GREEN (-3227 3850);
DISPLAY INVISIBLE (-3227 3850);
FORCEADD TAP..1
(-3225 3800);
FORCEPROP 3 LASTPIN (-3275 3800) SIG_NAME M_I_CPU1_SB_DQ<7>
J 0
(-3265 3810);
DISPLAY 0.659574 (-3265 3810);
PAINT MONO (-3265 3810);
DISPLAY INVISIBLE (-3265 3810);
FORCEPROP 1 LASTPIN (-3275 3800) BN 7
J 0
(-3287 3808);
DISPLAY 0.489362 (-3287 3808);
PAINT GREEN (-3287 3808);
FORCEPROP 2 LAST CDS_LIB mstr_standard
J 0
(-3225 3800);
DISPLAY 0.723404 (-3225 3800);
PAINT MONO (-3225 3800);
DISPLAY INVISIBLE (-3225 3800);
FORCEPROP 1 LAST BODY_TYPE PLUMBING
J 0
(-3225 3850);
DISPLAY 0.872340 (-3225 3850);
PAINT GREEN (-3225 3850);
DISPLAY INVISIBLE (-3225 3850);
FORCEPROP 1 LAST HDL_TAP TRUE
J 0
(-2900 3675);
DISPLAY 0.872340 (-2900 3675);
DISPLAY INVISIBLE (-2900 3675);
FORCEPROP 1 LAST PATH I202
J 0
(-3227 3800);
DISPLAY 0.872340 (-3227 3800);
PAINT GREEN (-3227 3800);
DISPLAY INVISIBLE (-3227 3800);
FORCEADD TAP..1
(-3225 3700);
FORCEPROP 3 LASTPIN (-3275 3700) SIG_NAME M_I_CPU1_SB_DQ<8>
J 0
(-3265 3710);
DISPLAY 0.659574 (-3265 3710);
PAINT MONO (-3265 3710);
DISPLAY INVISIBLE (-3265 3710);
FORCEPROP 1 LASTPIN (-3275 3700) BN 8
J 0
(-3287 3708);
DISPLAY 0.489362 (-3287 3708);
PAINT GREEN (-3287 3708);
FORCEPROP 2 LAST CDS_LIB mstr_standard
J 0
(-3225 3700);
DISPLAY 0.723404 (-3225 3700);
PAINT MONO (-3225 3700);
DISPLAY INVISIBLE (-3225 3700);
FORCEPROP 1 LAST BODY_TYPE PLUMBING
J 0
(-3225 3750);
DISPLAY 0.872340 (-3225 3750);
PAINT GREEN (-3225 3750);
DISPLAY INVISIBLE (-3225 3750);
FORCEPROP 1 LAST HDL_TAP TRUE
J 0
(-2900 3575);
DISPLAY 0.872340 (-2900 3575);
DISPLAY INVISIBLE (-2900 3575);
FORCEPROP 1 LAST PATH I203
J 0
(-3227 3700);
DISPLAY 0.872340 (-3227 3700);
PAINT GREEN (-3227 3700);
DISPLAY INVISIBLE (-3227 3700);
FORCEADD TAP..1
(-3225 3650);
FORCEPROP 3 LASTPIN (-3275 3650) SIG_NAME M_I_CPU1_SB_DQ<9>
J 0
(-3265 3660);
DISPLAY 0.659574 (-3265 3660);
PAINT MONO (-3265 3660);
DISPLAY INVISIBLE (-3265 3660);
FORCEPROP 1 LASTPIN (-3275 3650) BN 9
J 0
(-3287 3658);
DISPLAY 0.489362 (-3287 3658);
PAINT GREEN (-3287 3658);
FORCEPROP 2 LAST CDS_LIB mstr_standard
J 0
(-3225 3650);
DISPLAY 0.723404 (-3225 3650);
PAINT MONO (-3225 3650);
DISPLAY INVISIBLE (-3225 3650);
FORCEPROP 1 LAST BODY_TYPE PLUMBING
J 0
(-3225 3700);
DISPLAY 0.872340 (-3225 3700);
PAINT GREEN (-3225 3700);
DISPLAY INVISIBLE (-3225 3700);
FORCEPROP 1 LAST HDL_TAP TRUE
J 0
(-2900 3525);
DISPLAY 0.872340 (-2900 3525);
DISPLAY INVISIBLE (-2900 3525);
FORCEPROP 1 LAST PATH I204
J 0
(-3227 3650);
DISPLAY 0.872340 (-3227 3650);
PAINT GREEN (-3227 3650);
DISPLAY INVISIBLE (-3227 3650);
FORCEADD TAP..1
(-3225 3600);
FORCEPROP 3 LASTPIN (-3275 3600) SIG_NAME M_I_CPU1_SB_DQ<10>
J 0
(-3265 3610);
DISPLAY 0.659574 (-3265 3610);
PAINT MONO (-3265 3610);
DISPLAY INVISIBLE (-3265 3610);
FORCEPROP 1 LASTPIN (-3275 3600) BN 10
J 0
(-3287 3608);
DISPLAY 0.489362 (-3287 3608);
PAINT GREEN (-3287 3608);
FORCEPROP 2 LAST CDS_LIB mstr_standard
J 0
(-3225 3600);
DISPLAY 0.723404 (-3225 3600);
PAINT MONO (-3225 3600);
DISPLAY INVISIBLE (-3225 3600);
FORCEPROP 1 LAST BODY_TYPE PLUMBING
J 0
(-3225 3650);
DISPLAY 0.872340 (-3225 3650);
PAINT GREEN (-3225 3650);
DISPLAY INVISIBLE (-3225 3650);
FORCEPROP 1 LAST HDL_TAP TRUE
J 0
(-2900 3475);
DISPLAY 0.872340 (-2900 3475);
DISPLAY INVISIBLE (-2900 3475);
FORCEPROP 1 LAST PATH I205
J 0
(-3227 3600);
DISPLAY 0.872340 (-3227 3600);
PAINT GREEN (-3227 3600);
DISPLAY INVISIBLE (-3227 3600);
FORCEADD TAP..1
(-3225 3550);
FORCEPROP 3 LASTPIN (-3275 3550) SIG_NAME M_I_CPU1_SB_DQ<11>
J 0
(-3265 3560);
DISPLAY 0.659574 (-3265 3560);
PAINT MONO (-3265 3560);
DISPLAY INVISIBLE (-3265 3560);
FORCEPROP 1 LASTPIN (-3275 3550) BN 11
J 0
(-3287 3558);
DISPLAY 0.489362 (-3287 3558);
PAINT GREEN (-3287 3558);
FORCEPROP 2 LAST CDS_LIB mstr_standard
J 0
(-3225 3550);
DISPLAY 0.723404 (-3225 3550);
PAINT MONO (-3225 3550);
DISPLAY INVISIBLE (-3225 3550);
FORCEPROP 1 LAST BODY_TYPE PLUMBING
J 0
(-3225 3600);
DISPLAY 0.872340 (-3225 3600);
PAINT GREEN (-3225 3600);
DISPLAY INVISIBLE (-3225 3600);
FORCEPROP 1 LAST HDL_TAP TRUE
J 0
(-2900 3425);
DISPLAY 0.872340 (-2900 3425);
DISPLAY INVISIBLE (-2900 3425);
FORCEPROP 1 LAST PATH I206
J 0
(-3227 3550);
DISPLAY 0.872340 (-3227 3550);
PAINT GREEN (-3227 3550);
DISPLAY INVISIBLE (-3227 3550);
FORCEADD TAP..1
(-3225 3500);
FORCEPROP 3 LASTPIN (-3275 3500) SIG_NAME M_I_CPU1_SB_DQ<12>
J 0
(-3265 3510);
DISPLAY 0.659574 (-3265 3510);
PAINT MONO (-3265 3510);
DISPLAY INVISIBLE (-3265 3510);
FORCEPROP 1 LASTPIN (-3275 3500) BN 12
J 0
(-3287 3508);
DISPLAY 0.489362 (-3287 3508);
PAINT GREEN (-3287 3508);
FORCEPROP 2 LAST CDS_LIB mstr_standard
J 0
(-3225 3500);
DISPLAY 0.723404 (-3225 3500);
PAINT MONO (-3225 3500);
DISPLAY INVISIBLE (-3225 3500);
FORCEPROP 1 LAST BODY_TYPE PLUMBING
J 0
(-3225 3550);
DISPLAY 0.872340 (-3225 3550);
PAINT GREEN (-3225 3550);
DISPLAY INVISIBLE (-3225 3550);
FORCEPROP 1 LAST HDL_TAP TRUE
J 0
(-2900 3375);
DISPLAY 0.872340 (-2900 3375);
DISPLAY INVISIBLE (-2900 3375);
FORCEPROP 1 LAST PATH I207
J 0
(-3227 3500);
DISPLAY 0.872340 (-3227 3500);
PAINT GREEN (-3227 3500);
DISPLAY INVISIBLE (-3227 3500);
FORCEADD TAP..1
(-3225 3450);
FORCEPROP 3 LASTPIN (-3275 3450) SIG_NAME M_I_CPU1_SB_DQ<13>
J 0
(-3265 3460);
DISPLAY 0.659574 (-3265 3460);
PAINT MONO (-3265 3460);
DISPLAY INVISIBLE (-3265 3460);
FORCEPROP 1 LASTPIN (-3275 3450) BN 13
J 0
(-3287 3458);
DISPLAY 0.489362 (-3287 3458);
PAINT GREEN (-3287 3458);
FORCEPROP 2 LAST CDS_LIB mstr_standard
J 0
(-3225 3450);
DISPLAY 0.723404 (-3225 3450);
PAINT MONO (-3225 3450);
DISPLAY INVISIBLE (-3225 3450);
FORCEPROP 1 LAST BODY_TYPE PLUMBING
J 0
(-3225 3500);
DISPLAY 0.872340 (-3225 3500);
PAINT GREEN (-3225 3500);
DISPLAY INVISIBLE (-3225 3500);
FORCEPROP 1 LAST HDL_TAP TRUE
J 0
(-2900 3325);
DISPLAY 0.872340 (-2900 3325);
DISPLAY INVISIBLE (-2900 3325);
FORCEPROP 1 LAST PATH I208
J 0
(-3227 3450);
DISPLAY 0.872340 (-3227 3450);
PAINT GREEN (-3227 3450);
DISPLAY INVISIBLE (-3227 3450);
FORCEADD TAP..1
(-3225 3350);
FORCEPROP 3 LASTPIN (-3275 3350) SIG_NAME M_I_CPU1_SB_DQ<15>
J 0
(-3265 3360);
DISPLAY 0.659574 (-3265 3360);
PAINT MONO (-3265 3360);
DISPLAY INVISIBLE (-3265 3360);
FORCEPROP 1 LASTPIN (-3275 3350) BN 15
J 0
(-3287 3358);
DISPLAY 0.489362 (-3287 3358);
PAINT GREEN (-3287 3358);
FORCEPROP 2 LAST CDS_LIB mstr_standard
J 0
(-3225 3350);
DISPLAY 0.723404 (-3225 3350);
PAINT MONO (-3225 3350);
DISPLAY INVISIBLE (-3225 3350);
FORCEPROP 1 LAST BODY_TYPE PLUMBING
J 0
(-3225 3400);
DISPLAY 0.872340 (-3225 3400);
PAINT GREEN (-3225 3400);
DISPLAY INVISIBLE (-3225 3400);
FORCEPROP 1 LAST HDL_TAP TRUE
J 0
(-2900 3225);
DISPLAY 0.872340 (-2900 3225);
DISPLAY INVISIBLE (-2900 3225);
FORCEPROP 1 LAST PATH I209
J 0
(-3227 3350);
DISPLAY 0.872340 (-3227 3350);
PAINT GREEN (-3227 3350);
DISPLAY INVISIBLE (-3227 3350);
FORCEADD TAP..1
(-3225 3400);
FORCEPROP 3 LASTPIN (-3275 3400) SIG_NAME M_I_CPU1_SB_DQ<14>
J 0
(-3265 3410);
DISPLAY 0.659574 (-3265 3410);
PAINT MONO (-3265 3410);
DISPLAY INVISIBLE (-3265 3410);
FORCEPROP 1 LASTPIN (-3275 3400) BN 14
J 0
(-3287 3408);
DISPLAY 0.489362 (-3287 3408);
PAINT GREEN (-3287 3408);
FORCEPROP 2 LAST CDS_LIB mstr_standard
J 0
(-3225 3400);
DISPLAY 0.723404 (-3225 3400);
PAINT MONO (-3225 3400);
DISPLAY INVISIBLE (-3225 3400);
FORCEPROP 1 LAST BODY_TYPE PLUMBING
J 0
(-3225 3450);
DISPLAY 0.872340 (-3225 3450);
PAINT GREEN (-3225 3450);
DISPLAY INVISIBLE (-3225 3450);
FORCEPROP 1 LAST HDL_TAP TRUE
J 0
(-2900 3275);
DISPLAY 0.872340 (-2900 3275);
DISPLAY INVISIBLE (-2900 3275);
FORCEPROP 1 LAST PATH I210
J 0
(-3227 3400);
DISPLAY 0.872340 (-3227 3400);
PAINT GREEN (-3227 3400);
DISPLAY INVISIBLE (-3227 3400);
FORCEADD TAP..1
(-3225 3250);
FORCEPROP 3 LASTPIN (-3275 3250) SIG_NAME M_I_CPU1_SB_DQ<16>
J 0
(-3265 3260);
DISPLAY 0.659574 (-3265 3260);
PAINT MONO (-3265 3260);
DISPLAY INVISIBLE (-3265 3260);
FORCEPROP 1 LASTPIN (-3275 3250) BN 16
J 0
(-3287 3258);
DISPLAY 0.489362 (-3287 3258);
PAINT GREEN (-3287 3258);
FORCEPROP 2 LAST CDS_LIB mstr_standard
J 0
(-3225 3250);
DISPLAY 0.723404 (-3225 3250);
PAINT MONO (-3225 3250);
DISPLAY INVISIBLE (-3225 3250);
FORCEPROP 1 LAST BODY_TYPE PLUMBING
J 0
(-3225 3300);
DISPLAY 0.872340 (-3225 3300);
PAINT GREEN (-3225 3300);
DISPLAY INVISIBLE (-3225 3300);
FORCEPROP 1 LAST HDL_TAP TRUE
J 0
(-2900 3125);
DISPLAY 0.872340 (-2900 3125);
DISPLAY INVISIBLE (-2900 3125);
FORCEPROP 1 LAST PATH I211
J 0
(-3227 3250);
DISPLAY 0.872340 (-3227 3250);
PAINT GREEN (-3227 3250);
DISPLAY INVISIBLE (-3227 3250);
FORCEADD TAP..1
(-3225 3200);
FORCEPROP 3 LASTPIN (-3275 3200) SIG_NAME M_I_CPU1_SB_DQ<17>
J 0
(-3265 3210);
DISPLAY 0.659574 (-3265 3210);
PAINT MONO (-3265 3210);
DISPLAY INVISIBLE (-3265 3210);
FORCEPROP 1 LASTPIN (-3275 3200) BN 17
J 0
(-3287 3208);
DISPLAY 0.489362 (-3287 3208);
PAINT GREEN (-3287 3208);
FORCEPROP 2 LAST CDS_LIB mstr_standard
J 0
(-3225 3200);
DISPLAY 0.723404 (-3225 3200);
PAINT MONO (-3225 3200);
DISPLAY INVISIBLE (-3225 3200);
FORCEPROP 1 LAST BODY_TYPE PLUMBING
J 0
(-3225 3250);
DISPLAY 0.872340 (-3225 3250);
PAINT GREEN (-3225 3250);
DISPLAY INVISIBLE (-3225 3250);
FORCEPROP 1 LAST HDL_TAP TRUE
J 0
(-2900 3075);
DISPLAY 0.872340 (-2900 3075);
DISPLAY INVISIBLE (-2900 3075);
FORCEPROP 1 LAST PATH I212
J 0
(-3227 3200);
DISPLAY 0.872340 (-3227 3200);
PAINT GREEN (-3227 3200);
DISPLAY INVISIBLE (-3227 3200);
FORCEADD TAP..1
(-3225 3150);
FORCEPROP 3 LASTPIN (-3275 3150) SIG_NAME M_I_CPU1_SB_DQ<18>
J 0
(-3265 3160);
DISPLAY 0.659574 (-3265 3160);
PAINT MONO (-3265 3160);
DISPLAY INVISIBLE (-3265 3160);
FORCEPROP 1 LASTPIN (-3275 3150) BN 18
J 0
(-3287 3158);
DISPLAY 0.489362 (-3287 3158);
PAINT GREEN (-3287 3158);
FORCEPROP 2 LAST CDS_LIB mstr_standard
J 0
(-3225 3150);
DISPLAY 0.723404 (-3225 3150);
PAINT MONO (-3225 3150);
DISPLAY INVISIBLE (-3225 3150);
FORCEPROP 1 LAST BODY_TYPE PLUMBING
J 0
(-3225 3200);
DISPLAY 0.872340 (-3225 3200);
PAINT GREEN (-3225 3200);
DISPLAY INVISIBLE (-3225 3200);
FORCEPROP 1 LAST HDL_TAP TRUE
J 0
(-2900 3025);
DISPLAY 0.872340 (-2900 3025);
DISPLAY INVISIBLE (-2900 3025);
FORCEPROP 1 LAST PATH I213
J 0
(-3227 3150);
DISPLAY 0.872340 (-3227 3150);
PAINT GREEN (-3227 3150);
DISPLAY INVISIBLE (-3227 3150);
FORCEADD TAP..1
(-3225 3100);
FORCEPROP 3 LASTPIN (-3275 3100) SIG_NAME M_I_CPU1_SB_DQ<19>
J 0
(-3265 3110);
DISPLAY 0.659574 (-3265 3110);
PAINT MONO (-3265 3110);
DISPLAY INVISIBLE (-3265 3110);
FORCEPROP 1 LASTPIN (-3275 3100) BN 19
J 0
(-3287 3108);
DISPLAY 0.489362 (-3287 3108);
PAINT GREEN (-3287 3108);
FORCEPROP 2 LAST CDS_LIB mstr_standard
J 0
(-3225 3100);
DISPLAY 0.723404 (-3225 3100);
PAINT MONO (-3225 3100);
DISPLAY INVISIBLE (-3225 3100);
FORCEPROP 1 LAST BODY_TYPE PLUMBING
J 0
(-3225 3150);
DISPLAY 0.872340 (-3225 3150);
PAINT GREEN (-3225 3150);
DISPLAY INVISIBLE (-3225 3150);
FORCEPROP 1 LAST HDL_TAP TRUE
J 0
(-2900 2975);
DISPLAY 0.872340 (-2900 2975);
DISPLAY INVISIBLE (-2900 2975);
FORCEPROP 1 LAST PATH I214
J 0
(-3227 3100);
DISPLAY 0.872340 (-3227 3100);
PAINT GREEN (-3227 3100);
DISPLAY INVISIBLE (-3227 3100);
FORCEADD TAP..1
(-3225 3000);
FORCEPROP 3 LASTPIN (-3275 3000) SIG_NAME M_I_CPU1_SB_DQ<21>
J 0
(-3265 3010);
DISPLAY 0.659574 (-3265 3010);
PAINT MONO (-3265 3010);
DISPLAY INVISIBLE (-3265 3010);
FORCEPROP 1 LASTPIN (-3275 3000) BN 21
J 0
(-3287 3008);
DISPLAY 0.489362 (-3287 3008);
PAINT GREEN (-3287 3008);
FORCEPROP 2 LAST CDS_LIB mstr_standard
J 0
(-3225 3000);
DISPLAY 0.723404 (-3225 3000);
PAINT MONO (-3225 3000);
DISPLAY INVISIBLE (-3225 3000);
FORCEPROP 1 LAST BODY_TYPE PLUMBING
J 0
(-3225 3050);
DISPLAY 0.872340 (-3225 3050);
PAINT GREEN (-3225 3050);
DISPLAY INVISIBLE (-3225 3050);
FORCEPROP 1 LAST HDL_TAP TRUE
J 0
(-2900 2875);
DISPLAY 0.872340 (-2900 2875);
DISPLAY INVISIBLE (-2900 2875);
FORCEPROP 1 LAST PATH I215
J 0
(-3227 3000);
DISPLAY 0.872340 (-3227 3000);
PAINT GREEN (-3227 3000);
DISPLAY INVISIBLE (-3227 3000);
FORCEADD TAP..1
(-3225 2900);
FORCEPROP 3 LASTPIN (-3275 2900) SIG_NAME M_I_CPU1_SB_DQ<23>
J 0
(-3265 2910);
DISPLAY 0.659574 (-3265 2910);
PAINT MONO (-3265 2910);
DISPLAY INVISIBLE (-3265 2910);
FORCEPROP 1 LASTPIN (-3275 2900) BN 23
J 0
(-3287 2908);
DISPLAY 0.489362 (-3287 2908);
PAINT GREEN (-3287 2908);
FORCEPROP 2 LAST CDS_LIB mstr_standard
J 0
(-3225 2900);
DISPLAY 0.723404 (-3225 2900);
PAINT MONO (-3225 2900);
DISPLAY INVISIBLE (-3225 2900);
FORCEPROP 1 LAST BODY_TYPE PLUMBING
J 0
(-3225 2950);
DISPLAY 0.872340 (-3225 2950);
PAINT GREEN (-3225 2950);
DISPLAY INVISIBLE (-3225 2950);
FORCEPROP 1 LAST HDL_TAP TRUE
J 0
(-2900 2775);
DISPLAY 0.872340 (-2900 2775);
DISPLAY INVISIBLE (-2900 2775);
FORCEPROP 1 LAST PATH I216
J 0
(-3227 2900);
DISPLAY 0.872340 (-3227 2900);
PAINT GREEN (-3227 2900);
DISPLAY INVISIBLE (-3227 2900);
FORCEADD TAP..1
(-3225 3050);
FORCEPROP 3 LASTPIN (-3275 3050) SIG_NAME M_I_CPU1_SB_DQ<20>
J 0
(-3265 3060);
DISPLAY 0.659574 (-3265 3060);
PAINT MONO (-3265 3060);
DISPLAY INVISIBLE (-3265 3060);
FORCEPROP 1 LASTPIN (-3275 3050) BN 20
J 0
(-3287 3058);
DISPLAY 0.489362 (-3287 3058);
PAINT GREEN (-3287 3058);
FORCEPROP 2 LAST CDS_LIB mstr_standard
J 0
(-3225 3050);
DISPLAY 0.723404 (-3225 3050);
PAINT MONO (-3225 3050);
DISPLAY INVISIBLE (-3225 3050);
FORCEPROP 1 LAST BODY_TYPE PLUMBING
J 0
(-3225 3100);
DISPLAY 0.872340 (-3225 3100);
PAINT GREEN (-3225 3100);
DISPLAY INVISIBLE (-3225 3100);
FORCEPROP 1 LAST HDL_TAP TRUE
J 0
(-2900 2925);
DISPLAY 0.872340 (-2900 2925);
DISPLAY INVISIBLE (-2900 2925);
FORCEPROP 1 LAST PATH I217
J 0
(-3227 3050);
DISPLAY 0.872340 (-3227 3050);
PAINT GREEN (-3227 3050);
DISPLAY INVISIBLE (-3227 3050);
FORCEADD TAP..1
(-3225 2950);
FORCEPROP 3 LASTPIN (-3275 2950) SIG_NAME M_I_CPU1_SB_DQ<22>
J 0
(-3265 2960);
DISPLAY 0.659574 (-3265 2960);
PAINT MONO (-3265 2960);
DISPLAY INVISIBLE (-3265 2960);
FORCEPROP 1 LASTPIN (-3275 2950) BN 22
J 0
(-3287 2958);
DISPLAY 0.489362 (-3287 2958);
PAINT GREEN (-3287 2958);
FORCEPROP 2 LAST CDS_LIB mstr_standard
J 0
(-3225 2950);
DISPLAY 0.723404 (-3225 2950);
PAINT MONO (-3225 2950);
DISPLAY INVISIBLE (-3225 2950);
FORCEPROP 1 LAST BODY_TYPE PLUMBING
J 0
(-3225 3000);
DISPLAY 0.872340 (-3225 3000);
PAINT GREEN (-3225 3000);
DISPLAY INVISIBLE (-3225 3000);
FORCEPROP 1 LAST HDL_TAP TRUE
J 0
(-2900 2825);
DISPLAY 0.872340 (-2900 2825);
DISPLAY INVISIBLE (-2900 2825);
FORCEPROP 1 LAST PATH I218
J 0
(-3227 2950);
DISPLAY 0.872340 (-3227 2950);
PAINT GREEN (-3227 2950);
DISPLAY INVISIBLE (-3227 2950);
FORCEADD TAP..1
(-3225 2800);
FORCEPROP 3 LASTPIN (-3275 2800) SIG_NAME M_I_CPU1_SB_DQ<24>
J 0
(-3265 2810);
DISPLAY 0.659574 (-3265 2810);
PAINT MONO (-3265 2810);
DISPLAY INVISIBLE (-3265 2810);
FORCEPROP 1 LASTPIN (-3275 2800) BN 24
J 0
(-3287 2808);
DISPLAY 0.489362 (-3287 2808);
PAINT GREEN (-3287 2808);
FORCEPROP 2 LAST CDS_LIB mstr_standard
J 0
(-3225 2800);
DISPLAY 0.723404 (-3225 2800);
PAINT MONO (-3225 2800);
DISPLAY INVISIBLE (-3225 2800);
FORCEPROP 1 LAST BODY_TYPE PLUMBING
J 0
(-3225 2850);
DISPLAY 0.872340 (-3225 2850);
PAINT GREEN (-3225 2850);
DISPLAY INVISIBLE (-3225 2850);
FORCEPROP 1 LAST HDL_TAP TRUE
J 0
(-2900 2675);
DISPLAY 0.872340 (-2900 2675);
DISPLAY INVISIBLE (-2900 2675);
FORCEPROP 1 LAST PATH I219
J 0
(-3227 2800);
DISPLAY 0.872340 (-3227 2800);
PAINT GREEN (-3227 2800);
DISPLAY INVISIBLE (-3227 2800);
FORCEADD TAP..1
(-3225 2750);
FORCEPROP 3 LASTPIN (-3275 2750) SIG_NAME M_I_CPU1_SB_DQ<25>
J 0
(-3265 2760);
DISPLAY 0.659574 (-3265 2760);
PAINT MONO (-3265 2760);
DISPLAY INVISIBLE (-3265 2760);
FORCEPROP 1 LASTPIN (-3275 2750) BN 25
J 0
(-3287 2758);
DISPLAY 0.489362 (-3287 2758);
PAINT GREEN (-3287 2758);
FORCEPROP 2 LAST CDS_LIB mstr_standard
J 0
(-3225 2750);
DISPLAY 0.723404 (-3225 2750);
PAINT MONO (-3225 2750);
DISPLAY INVISIBLE (-3225 2750);
FORCEPROP 1 LAST BODY_TYPE PLUMBING
J 0
(-3225 2800);
DISPLAY 0.872340 (-3225 2800);
PAINT GREEN (-3225 2800);
DISPLAY INVISIBLE (-3225 2800);
FORCEPROP 1 LAST HDL_TAP TRUE
J 0
(-2900 2625);
DISPLAY 0.872340 (-2900 2625);
DISPLAY INVISIBLE (-2900 2625);
FORCEPROP 1 LAST PATH I220
J 0
(-3227 2750);
DISPLAY 0.872340 (-3227 2750);
PAINT GREEN (-3227 2750);
DISPLAY INVISIBLE (-3227 2750);
FORCEADD TAP..1
(-3225 2700);
FORCEPROP 3 LASTPIN (-3275 2700) SIG_NAME M_I_CPU1_SB_DQ<26>
J 0
(-3265 2710);
DISPLAY 0.659574 (-3265 2710);
PAINT MONO (-3265 2710);
DISPLAY INVISIBLE (-3265 2710);
FORCEPROP 1 LASTPIN (-3275 2700) BN 26
J 0
(-3287 2708);
DISPLAY 0.489362 (-3287 2708);
PAINT GREEN (-3287 2708);
FORCEPROP 2 LAST CDS_LIB mstr_standard
J 0
(-3225 2700);
DISPLAY 0.723404 (-3225 2700);
PAINT MONO (-3225 2700);
DISPLAY INVISIBLE (-3225 2700);
FORCEPROP 1 LAST BODY_TYPE PLUMBING
J 0
(-3225 2750);
DISPLAY 0.872340 (-3225 2750);
PAINT GREEN (-3225 2750);
DISPLAY INVISIBLE (-3225 2750);
FORCEPROP 1 LAST HDL_TAP TRUE
J 0
(-2900 2575);
DISPLAY 0.872340 (-2900 2575);
DISPLAY INVISIBLE (-2900 2575);
FORCEPROP 1 LAST PATH I221
J 0
(-3227 2700);
DISPLAY 0.872340 (-3227 2700);
PAINT GREEN (-3227 2700);
DISPLAY INVISIBLE (-3227 2700);
FORCEADD TAP..1
(-3225 2600);
FORCEPROP 3 LASTPIN (-3275 2600) SIG_NAME M_I_CPU1_SB_DQ<28>
J 0
(-3265 2610);
DISPLAY 0.659574 (-3265 2610);
PAINT MONO (-3265 2610);
DISPLAY INVISIBLE (-3265 2610);
FORCEPROP 1 LASTPIN (-3275 2600) BN 28
J 0
(-3287 2608);
DISPLAY 0.489362 (-3287 2608);
PAINT GREEN (-3287 2608);
FORCEPROP 2 LAST CDS_LIB mstr_standard
J 0
(-3225 2600);
DISPLAY 0.723404 (-3225 2600);
PAINT MONO (-3225 2600);
DISPLAY INVISIBLE (-3225 2600);
FORCEPROP 1 LAST BODY_TYPE PLUMBING
J 0
(-3225 2650);
DISPLAY 0.872340 (-3225 2650);
PAINT GREEN (-3225 2650);
DISPLAY INVISIBLE (-3225 2650);
FORCEPROP 1 LAST HDL_TAP TRUE
J 0
(-2900 2475);
DISPLAY 0.872340 (-2900 2475);
DISPLAY INVISIBLE (-2900 2475);
FORCEPROP 1 LAST PATH I222
J 0
(-3227 2600);
DISPLAY 0.872340 (-3227 2600);
PAINT GREEN (-3227 2600);
DISPLAY INVISIBLE (-3227 2600);
FORCEADD TAP..1
(-3225 2650);
FORCEPROP 3 LASTPIN (-3275 2650) SIG_NAME M_I_CPU1_SB_DQ<27>
J 0
(-3265 2660);
DISPLAY 0.659574 (-3265 2660);
PAINT MONO (-3265 2660);
DISPLAY INVISIBLE (-3265 2660);
FORCEPROP 1 LASTPIN (-3275 2650) BN 27
J 0
(-3287 2658);
DISPLAY 0.489362 (-3287 2658);
PAINT GREEN (-3287 2658);
FORCEPROP 2 LAST CDS_LIB mstr_standard
J 0
(-3225 2650);
DISPLAY 0.723404 (-3225 2650);
PAINT MONO (-3225 2650);
DISPLAY INVISIBLE (-3225 2650);
FORCEPROP 1 LAST BODY_TYPE PLUMBING
J 0
(-3225 2700);
DISPLAY 0.872340 (-3225 2700);
PAINT GREEN (-3225 2700);
DISPLAY INVISIBLE (-3225 2700);
FORCEPROP 1 LAST HDL_TAP TRUE
J 0
(-2900 2525);
DISPLAY 0.872340 (-2900 2525);
DISPLAY INVISIBLE (-2900 2525);
FORCEPROP 1 LAST PATH I223
J 0
(-3227 2650);
DISPLAY 0.872340 (-3227 2650);
PAINT GREEN (-3227 2650);
DISPLAY INVISIBLE (-3227 2650);
FORCEADD TAP..1
(-3225 2500);
FORCEPROP 3 LASTPIN (-3275 2500) SIG_NAME M_I_CPU1_SB_DQ<30>
J 0
(-3265 2510);
DISPLAY 0.659574 (-3265 2510);
PAINT MONO (-3265 2510);
DISPLAY INVISIBLE (-3265 2510);
FORCEPROP 1 LASTPIN (-3275 2500) BN 30
J 0
(-3287 2508);
DISPLAY 0.489362 (-3287 2508);
PAINT GREEN (-3287 2508);
FORCEPROP 2 LAST CDS_LIB mstr_standard
J 0
(-3225 2500);
DISPLAY 0.723404 (-3225 2500);
PAINT MONO (-3225 2500);
DISPLAY INVISIBLE (-3225 2500);
FORCEPROP 1 LAST BODY_TYPE PLUMBING
J 0
(-3225 2550);
DISPLAY 0.872340 (-3225 2550);
PAINT GREEN (-3225 2550);
DISPLAY INVISIBLE (-3225 2550);
FORCEPROP 1 LAST HDL_TAP TRUE
J 0
(-2900 2375);
DISPLAY 0.872340 (-2900 2375);
DISPLAY INVISIBLE (-2900 2375);
FORCEPROP 1 LAST PATH I224
J 0
(-3227 2500);
DISPLAY 0.872340 (-3227 2500);
PAINT GREEN (-3227 2500);
DISPLAY INVISIBLE (-3227 2500);
FORCEADD TAP..1
(-3225 2550);
FORCEPROP 3 LASTPIN (-3275 2550) SIG_NAME M_I_CPU1_SB_DQ<29>
J 0
(-3265 2560);
DISPLAY 0.659574 (-3265 2560);
PAINT MONO (-3265 2560);
DISPLAY INVISIBLE (-3265 2560);
FORCEPROP 1 LASTPIN (-3275 2550) BN 29
J 0
(-3287 2558);
DISPLAY 0.489362 (-3287 2558);
PAINT GREEN (-3287 2558);
FORCEPROP 2 LAST CDS_LIB mstr_standard
J 0
(-3225 2550);
DISPLAY 0.723404 (-3225 2550);
PAINT MONO (-3225 2550);
DISPLAY INVISIBLE (-3225 2550);
FORCEPROP 1 LAST BODY_TYPE PLUMBING
J 0
(-3225 2600);
DISPLAY 0.872340 (-3225 2600);
PAINT GREEN (-3225 2600);
DISPLAY INVISIBLE (-3225 2600);
FORCEPROP 1 LAST HDL_TAP TRUE
J 0
(-2900 2425);
DISPLAY 0.872340 (-2900 2425);
DISPLAY INVISIBLE (-2900 2425);
FORCEPROP 1 LAST PATH I225
J 0
(-3227 2550);
DISPLAY 0.872340 (-3227 2550);
PAINT GREEN (-3227 2550);
DISPLAY INVISIBLE (-3227 2550);
FORCEADD TAP..1
(-3225 2450);
FORCEPROP 3 LASTPIN (-3275 2450) SIG_NAME M_I_CPU1_SB_DQ<31>
J 0
(-3265 2460);
DISPLAY 0.659574 (-3265 2460);
PAINT MONO (-3265 2460);
DISPLAY INVISIBLE (-3265 2460);
FORCEPROP 1 LASTPIN (-3275 2450) BN 31
J 0
(-3287 2458);
DISPLAY 0.489362 (-3287 2458);
PAINT GREEN (-3287 2458);
FORCEPROP 2 LAST CDS_LIB mstr_standard
J 0
(-3225 2450);
DISPLAY 0.723404 (-3225 2450);
PAINT MONO (-3225 2450);
DISPLAY INVISIBLE (-3225 2450);
FORCEPROP 1 LAST BODY_TYPE PLUMBING
J 0
(-3225 2500);
DISPLAY 0.872340 (-3225 2500);
PAINT GREEN (-3225 2500);
DISPLAY INVISIBLE (-3225 2500);
FORCEPROP 1 LAST HDL_TAP TRUE
J 0
(-2900 2325);
DISPLAY 0.872340 (-2900 2325);
DISPLAY INVISIBLE (-2900 2325);
FORCEPROP 1 LAST PATH I226
J 0
(-3227 2450);
DISPLAY 0.872340 (-3227 2450);
PAINT GREEN (-3227 2450);
DISPLAY INVISIBLE (-3227 2450);
FORCEADD TAP..1
(-3225 2350);
FORCEPROP 3 LASTPIN (-3275 2350) SIG_NAME M_I_CPU1_SA_CB<0>
J 0
(-3265 2360);
DISPLAY 0.659574 (-3265 2360);
PAINT MONO (-3265 2360);
DISPLAY INVISIBLE (-3265 2360);
FORCEPROP 1 LASTPIN (-3275 2350) BN 0
J 0
(-3287 2358);
DISPLAY 0.489362 (-3287 2358);
PAINT GREEN (-3287 2358);
FORCEPROP 2 LAST CDS_LIB mstr_standard
J 2
(-3225 2350);
DISPLAY 0.723404 (-3225 2350);
PAINT MONO (-3225 2350);
DISPLAY INVISIBLE (-3225 2350);
FORCEPROP 1 LAST BODY_TYPE PLUMBING
J 0
(-3225 2400);
DISPLAY 0.872340 (-3225 2400);
PAINT GREEN (-3225 2400);
DISPLAY INVISIBLE (-3225 2400);
FORCEPROP 1 LAST HDL_TAP TRUE
J 0
(-2900 2225);
DISPLAY 0.872340 (-2900 2225);
DISPLAY INVISIBLE (-2900 2225);
FORCEPROP 1 LAST PATH I227
J 0
(-3227 2350);
DISPLAY 0.872340 (-3227 2350);
PAINT GREEN (-3227 2350);
DISPLAY INVISIBLE (-3227 2350);
FORCEADD TAP..1
(-3225 2300);
FORCEPROP 3 LASTPIN (-3275 2300) SIG_NAME M_I_CPU1_SA_CB<1>
J 0
(-3265 2310);
DISPLAY 0.659574 (-3265 2310);
PAINT MONO (-3265 2310);
DISPLAY INVISIBLE (-3265 2310);
FORCEPROP 1 LASTPIN (-3275 2300) BN 1
J 0
(-3287 2308);
DISPLAY 0.489362 (-3287 2308);
PAINT GREEN (-3287 2308);
FORCEPROP 2 LAST CDS_LIB mstr_standard
J 2
(-3225 2300);
DISPLAY 0.723404 (-3225 2300);
PAINT MONO (-3225 2300);
DISPLAY INVISIBLE (-3225 2300);
FORCEPROP 1 LAST BODY_TYPE PLUMBING
J 0
(-3225 2350);
DISPLAY 0.872340 (-3225 2350);
PAINT GREEN (-3225 2350);
DISPLAY INVISIBLE (-3225 2350);
FORCEPROP 1 LAST HDL_TAP TRUE
J 0
(-2900 2175);
DISPLAY 0.872340 (-2900 2175);
DISPLAY INVISIBLE (-2900 2175);
FORCEPROP 1 LAST PATH I228
J 0
(-3227 2300);
DISPLAY 0.872340 (-3227 2300);
PAINT GREEN (-3227 2300);
DISPLAY INVISIBLE (-3227 2300);
FORCEADD TAP..1
(-3225 2200);
FORCEPROP 3 LASTPIN (-3275 2200) SIG_NAME M_I_CPU1_SA_CB<3>
J 0
(-3265 2210);
DISPLAY 0.659574 (-3265 2210);
PAINT MONO (-3265 2210);
DISPLAY INVISIBLE (-3265 2210);
FORCEPROP 1 LASTPIN (-3275 2200) BN 3
J 0
(-3287 2208);
DISPLAY 0.489362 (-3287 2208);
PAINT GREEN (-3287 2208);
FORCEPROP 2 LAST CDS_LIB mstr_standard
J 2
(-3225 2200);
DISPLAY 0.723404 (-3225 2200);
PAINT MONO (-3225 2200);
DISPLAY INVISIBLE (-3225 2200);
FORCEPROP 1 LAST BODY_TYPE PLUMBING
J 0
(-3225 2250);
DISPLAY 0.872340 (-3225 2250);
PAINT GREEN (-3225 2250);
DISPLAY INVISIBLE (-3225 2250);
FORCEPROP 1 LAST HDL_TAP TRUE
J 0
(-2900 2075);
DISPLAY 0.872340 (-2900 2075);
DISPLAY INVISIBLE (-2900 2075);
FORCEPROP 1 LAST PATH I229
J 0
(-3227 2200);
DISPLAY 0.872340 (-3227 2200);
PAINT GREEN (-3227 2200);
DISPLAY INVISIBLE (-3227 2200);
FORCEADD TAP..1
(-3225 2250);
FORCEPROP 3 LASTPIN (-3275 2250) SIG_NAME M_I_CPU1_SA_CB<2>
J 0
(-3265 2260);
DISPLAY 0.659574 (-3265 2260);
PAINT MONO (-3265 2260);
DISPLAY INVISIBLE (-3265 2260);
FORCEPROP 1 LASTPIN (-3275 2250) BN 2
J 0
(-3287 2258);
DISPLAY 0.489362 (-3287 2258);
PAINT GREEN (-3287 2258);
FORCEPROP 2 LAST CDS_LIB mstr_standard
J 2
(-3225 2250);
DISPLAY 0.723404 (-3225 2250);
PAINT MONO (-3225 2250);
DISPLAY INVISIBLE (-3225 2250);
FORCEPROP 1 LAST BODY_TYPE PLUMBING
J 0
(-3225 2300);
DISPLAY 0.872340 (-3225 2300);
PAINT GREEN (-3225 2300);
DISPLAY INVISIBLE (-3225 2300);
FORCEPROP 1 LAST HDL_TAP TRUE
J 0
(-2900 2125);
DISPLAY 0.872340 (-2900 2125);
DISPLAY INVISIBLE (-2900 2125);
FORCEPROP 1 LAST PATH I230
J 0
(-3227 2250);
DISPLAY 0.872340 (-3227 2250);
PAINT GREEN (-3227 2250);
DISPLAY INVISIBLE (-3227 2250);
FORCEADD TAP..1
(-3225 2050);
FORCEPROP 3 LASTPIN (-3275 2050) SIG_NAME M_I_CPU1_SA_CB<6>
J 0
(-3265 2060);
DISPLAY 0.659574 (-3265 2060);
PAINT MONO (-3265 2060);
DISPLAY INVISIBLE (-3265 2060);
FORCEPROP 1 LASTPIN (-3275 2050) BN 6
J 0
(-3287 2058);
DISPLAY 0.489362 (-3287 2058);
PAINT GREEN (-3287 2058);
FORCEPROP 2 LAST CDS_LIB mstr_standard
J 2
(-3225 2050);
DISPLAY 0.723404 (-3225 2050);
PAINT MONO (-3225 2050);
DISPLAY INVISIBLE (-3225 2050);
FORCEPROP 1 LAST BODY_TYPE PLUMBING
J 0
(-3225 2100);
DISPLAY 0.872340 (-3225 2100);
PAINT GREEN (-3225 2100);
DISPLAY INVISIBLE (-3225 2100);
FORCEPROP 1 LAST HDL_TAP TRUE
J 0
(-2900 1925);
DISPLAY 0.872340 (-2900 1925);
DISPLAY INVISIBLE (-2900 1925);
FORCEPROP 1 LAST PATH I231
J 0
(-3227 2050);
DISPLAY 0.872340 (-3227 2050);
PAINT GREEN (-3227 2050);
DISPLAY INVISIBLE (-3227 2050);
FORCEADD TAP..1
(-3225 2100);
FORCEPROP 3 LASTPIN (-3275 2100) SIG_NAME M_I_CPU1_SA_CB<5>
J 0
(-3265 2110);
DISPLAY 0.659574 (-3265 2110);
PAINT MONO (-3265 2110);
DISPLAY INVISIBLE (-3265 2110);
FORCEPROP 1 LASTPIN (-3275 2100) BN 5
J 0
(-3287 2108);
DISPLAY 0.489362 (-3287 2108);
PAINT GREEN (-3287 2108);
FORCEPROP 2 LAST CDS_LIB mstr_standard
J 2
(-3225 2100);
DISPLAY 0.723404 (-3225 2100);
PAINT MONO (-3225 2100);
DISPLAY INVISIBLE (-3225 2100);
FORCEPROP 1 LAST BODY_TYPE PLUMBING
J 0
(-3225 2150);
DISPLAY 0.872340 (-3225 2150);
PAINT GREEN (-3225 2150);
DISPLAY INVISIBLE (-3225 2150);
FORCEPROP 1 LAST HDL_TAP TRUE
J 0
(-2900 1975);
DISPLAY 0.872340 (-2900 1975);
DISPLAY INVISIBLE (-2900 1975);
FORCEPROP 1 LAST PATH I232
J 0
(-3227 2100);
DISPLAY 0.872340 (-3227 2100);
PAINT GREEN (-3227 2100);
DISPLAY INVISIBLE (-3227 2100);
FORCEADD TAP..1
(-3225 2150);
FORCEPROP 3 LASTPIN (-3275 2150) SIG_NAME M_I_CPU1_SA_CB<4>
J 0
(-3265 2160);
DISPLAY 0.659574 (-3265 2160);
PAINT MONO (-3265 2160);
DISPLAY INVISIBLE (-3265 2160);
FORCEPROP 1 LASTPIN (-3275 2150) BN 4
J 0
(-3287 2158);
DISPLAY 0.489362 (-3287 2158);
PAINT GREEN (-3287 2158);
FORCEPROP 2 LAST CDS_LIB mstr_standard
J 2
(-3225 2150);
DISPLAY 0.723404 (-3225 2150);
PAINT MONO (-3225 2150);
DISPLAY INVISIBLE (-3225 2150);
FORCEPROP 1 LAST BODY_TYPE PLUMBING
J 0
(-3225 2200);
DISPLAY 0.872340 (-3225 2200);
PAINT GREEN (-3225 2200);
DISPLAY INVISIBLE (-3225 2200);
FORCEPROP 1 LAST HDL_TAP TRUE
J 0
(-2900 2025);
DISPLAY 0.872340 (-2900 2025);
DISPLAY INVISIBLE (-2900 2025);
FORCEPROP 1 LAST PATH I233
J 0
(-3227 2150);
DISPLAY 0.872340 (-3227 2150);
PAINT GREEN (-3227 2150);
DISPLAY INVISIBLE (-3227 2150);
FORCEADD OFFPAGE..6
R 2
(-2625 1950);
FORCEPROP 2 LAST $XR0 105 
J 0
(-2411 1950);
DISPLAY 0.638298 (-2411 1950);
PAINT MONO (-2411 1950);
FORCEPROP 2 LAST PATH I234
J 0
(-2400 2000);
DISPLAY 1.021277 (-2400 2000);
DISPLAY INVISIBLE (-2400 2000);
FORCEPROP 1 LAST COMMENT_BODY TRUE
J 2
(-2725 1875);
DISPLAY 0.872340 (-2725 1875);
PAINT GREEN (-2725 1875);
DISPLAY INVISIBLE (-2725 1875);
FORCEPROP 1 LAST OFFPAGE TRUE
J 2
(-2950 1825);
DISPLAY 0.872340 (-2950 1825);
PAINT GREEN (-2950 1825);
DISPLAY INVISIBLE (-2950 1825);
FORCEPROP 2 LAST CDS_LIB mstr_standard
J 2
(-2625 1950);
DISPLAY 0.723404 (-2625 1950);
PAINT MONO (-2625 1950);
DISPLAY INVISIBLE (-2625 1950);
FORCEADD TAP..1
(-3225 1900);
FORCEPROP 3 LASTPIN (-3275 1900) SIG_NAME M_I_CPU1_SB_CB<0>
J 0
(-3265 1910);
DISPLAY 0.659574 (-3265 1910);
PAINT MONO (-3265 1910);
DISPLAY INVISIBLE (-3265 1910);
FORCEPROP 1 LASTPIN (-3275 1900) BN 0
J 0
(-3287 1908);
DISPLAY 0.489362 (-3287 1908);
PAINT GREEN (-3287 1908);
FORCEPROP 2 LAST CDS_LIB mstr_standard
J 2
(-3225 1900);
DISPLAY 0.723404 (-3225 1900);
PAINT MONO (-3225 1900);
DISPLAY INVISIBLE (-3225 1900);
FORCEPROP 1 LAST BODY_TYPE PLUMBING
J 0
(-3225 1950);
DISPLAY 0.872340 (-3225 1950);
PAINT GREEN (-3225 1950);
DISPLAY INVISIBLE (-3225 1950);
FORCEPROP 1 LAST HDL_TAP TRUE
J 0
(-2900 1775);
DISPLAY 0.872340 (-2900 1775);
DISPLAY INVISIBLE (-2900 1775);
FORCEPROP 1 LAST PATH I235
J 0
(-3227 1900);
DISPLAY 0.872340 (-3227 1900);
PAINT GREEN (-3227 1900);
DISPLAY INVISIBLE (-3227 1900);
FORCEADD TAP..1
(-3225 2000);
FORCEPROP 3 LASTPIN (-3275 2000) SIG_NAME M_I_CPU1_SA_CB<7>
J 0
(-3265 2010);
DISPLAY 0.659574 (-3265 2010);
PAINT MONO (-3265 2010);
DISPLAY INVISIBLE (-3265 2010);
FORCEPROP 1 LASTPIN (-3275 2000) BN 7
J 0
(-3287 2008);
DISPLAY 0.489362 (-3287 2008);
PAINT GREEN (-3287 2008);
FORCEPROP 2 LAST CDS_LIB mstr_standard
J 2
(-3225 2000);
DISPLAY 0.723404 (-3225 2000);
PAINT MONO (-3225 2000);
DISPLAY INVISIBLE (-3225 2000);
FORCEPROP 1 LAST BODY_TYPE PLUMBING
J 0
(-3225 2050);
DISPLAY 0.872340 (-3225 2050);
PAINT GREEN (-3225 2050);
DISPLAY INVISIBLE (-3225 2050);
FORCEPROP 1 LAST HDL_TAP TRUE
J 0
(-2900 1875);
DISPLAY 0.872340 (-2900 1875);
DISPLAY INVISIBLE (-2900 1875);
FORCEPROP 1 LAST PATH I236
J 0
(-3227 2000);
DISPLAY 0.872340 (-3227 2000);
PAINT GREEN (-3227 2000);
DISPLAY INVISIBLE (-3227 2000);
FORCEADD TAP..1
(-3225 1800);
FORCEPROP 3 LASTPIN (-3275 1800) SIG_NAME M_I_CPU1_SB_CB<2>
J 0
(-3265 1810);
DISPLAY 0.659574 (-3265 1810);
PAINT MONO (-3265 1810);
DISPLAY INVISIBLE (-3265 1810);
FORCEPROP 1 LASTPIN (-3275 1800) BN 2
J 0
(-3287 1808);
DISPLAY 0.489362 (-3287 1808);
PAINT GREEN (-3287 1808);
FORCEPROP 2 LAST CDS_LIB mstr_standard
J 2
(-3225 1800);
DISPLAY 0.723404 (-3225 1800);
PAINT MONO (-3225 1800);
DISPLAY INVISIBLE (-3225 1800);
FORCEPROP 1 LAST BODY_TYPE PLUMBING
J 0
(-3225 1850);
DISPLAY 0.872340 (-3225 1850);
PAINT GREEN (-3225 1850);
DISPLAY INVISIBLE (-3225 1850);
FORCEPROP 1 LAST HDL_TAP TRUE
J 0
(-2900 1675);
DISPLAY 0.872340 (-2900 1675);
DISPLAY INVISIBLE (-2900 1675);
FORCEPROP 1 LAST PATH I237
J 0
(-3227 1800);
DISPLAY 0.872340 (-3227 1800);
PAINT GREEN (-3227 1800);
DISPLAY INVISIBLE (-3227 1800);
FORCEADD TAP..1
(-3225 1850);
FORCEPROP 3 LASTPIN (-3275 1850) SIG_NAME M_I_CPU1_SB_CB<1>
J 0
(-3265 1860);
DISPLAY 0.659574 (-3265 1860);
PAINT MONO (-3265 1860);
DISPLAY INVISIBLE (-3265 1860);
FORCEPROP 1 LASTPIN (-3275 1850) BN 1
J 0
(-3287 1858);
DISPLAY 0.489362 (-3287 1858);
PAINT GREEN (-3287 1858);
FORCEPROP 2 LAST CDS_LIB mstr_standard
J 2
(-3225 1850);
DISPLAY 0.723404 (-3225 1850);
PAINT MONO (-3225 1850);
DISPLAY INVISIBLE (-3225 1850);
FORCEPROP 1 LAST BODY_TYPE PLUMBING
J 0
(-3225 1900);
DISPLAY 0.872340 (-3225 1900);
PAINT GREEN (-3225 1900);
DISPLAY INVISIBLE (-3225 1900);
FORCEPROP 1 LAST HDL_TAP TRUE
J 0
(-2900 1725);
DISPLAY 0.872340 (-2900 1725);
DISPLAY INVISIBLE (-2900 1725);
FORCEPROP 1 LAST PATH I238
J 0
(-3227 1850);
DISPLAY 0.872340 (-3227 1850);
PAINT GREEN (-3227 1850);
DISPLAY INVISIBLE (-3227 1850);
FORCEADD TAP..1
(-3225 1750);
FORCEPROP 3 LASTPIN (-3275 1750) SIG_NAME M_I_CPU1_SB_CB<3>
J 0
(-3265 1760);
DISPLAY 0.659574 (-3265 1760);
PAINT MONO (-3265 1760);
DISPLAY INVISIBLE (-3265 1760);
FORCEPROP 1 LASTPIN (-3275 1750) BN 3
J 0
(-3287 1758);
DISPLAY 0.489362 (-3287 1758);
PAINT GREEN (-3287 1758);
FORCEPROP 2 LAST CDS_LIB mstr_standard
J 2
(-3225 1750);
DISPLAY 0.723404 (-3225 1750);
PAINT MONO (-3225 1750);
DISPLAY INVISIBLE (-3225 1750);
FORCEPROP 1 LAST BODY_TYPE PLUMBING
J 0
(-3225 1800);
DISPLAY 0.872340 (-3225 1800);
PAINT GREEN (-3225 1800);
DISPLAY INVISIBLE (-3225 1800);
FORCEPROP 1 LAST HDL_TAP TRUE
J 0
(-2900 1625);
DISPLAY 0.872340 (-2900 1625);
DISPLAY INVISIBLE (-2900 1625);
FORCEPROP 1 LAST PATH I239
J 0
(-3227 1750);
DISPLAY 0.872340 (-3227 1750);
PAINT GREEN (-3227 1750);
DISPLAY INVISIBLE (-3227 1750);
FORCEADD TAP..1
(-3225 1700);
FORCEPROP 3 LASTPIN (-3275 1700) SIG_NAME M_I_CPU1_SB_CB<4>
J 0
(-3265 1710);
DISPLAY 0.659574 (-3265 1710);
PAINT MONO (-3265 1710);
DISPLAY INVISIBLE (-3265 1710);
FORCEPROP 1 LASTPIN (-3275 1700) BN 4
J 0
(-3287 1708);
DISPLAY 0.489362 (-3287 1708);
PAINT GREEN (-3287 1708);
FORCEPROP 2 LAST CDS_LIB mstr_standard
J 2
(-3225 1700);
DISPLAY 0.723404 (-3225 1700);
PAINT MONO (-3225 1700);
DISPLAY INVISIBLE (-3225 1700);
FORCEPROP 1 LAST BODY_TYPE PLUMBING
J 0
(-3225 1750);
DISPLAY 0.872340 (-3225 1750);
PAINT GREEN (-3225 1750);
DISPLAY INVISIBLE (-3225 1750);
FORCEPROP 1 LAST HDL_TAP TRUE
J 0
(-2900 1575);
DISPLAY 0.872340 (-2900 1575);
DISPLAY INVISIBLE (-2900 1575);
FORCEPROP 1 LAST PATH I240
J 0
(-3227 1700);
DISPLAY 0.872340 (-3227 1700);
PAINT GREEN (-3227 1700);
DISPLAY INVISIBLE (-3227 1700);
FORCEADD TAP..1
(-3225 1650);
FORCEPROP 3 LASTPIN (-3275 1650) SIG_NAME M_I_CPU1_SB_CB<5>
J 0
(-3265 1660);
DISPLAY 0.659574 (-3265 1660);
PAINT MONO (-3265 1660);
DISPLAY INVISIBLE (-3265 1660);
FORCEPROP 1 LASTPIN (-3275 1650) BN 5
J 0
(-3287 1658);
DISPLAY 0.489362 (-3287 1658);
PAINT GREEN (-3287 1658);
FORCEPROP 2 LAST CDS_LIB mstr_standard
J 2
(-3225 1650);
DISPLAY 0.723404 (-3225 1650);
PAINT MONO (-3225 1650);
DISPLAY INVISIBLE (-3225 1650);
FORCEPROP 1 LAST BODY_TYPE PLUMBING
J 0
(-3225 1700);
DISPLAY 0.872340 (-3225 1700);
PAINT GREEN (-3225 1700);
DISPLAY INVISIBLE (-3225 1700);
FORCEPROP 1 LAST HDL_TAP TRUE
J 0
(-2900 1525);
DISPLAY 0.872340 (-2900 1525);
DISPLAY INVISIBLE (-2900 1525);
FORCEPROP 1 LAST PATH I241
J 0
(-3227 1650);
DISPLAY 0.872340 (-3227 1650);
PAINT GREEN (-3227 1650);
DISPLAY INVISIBLE (-3227 1650);
FORCEADD TAP..1
(-3225 1550);
FORCEPROP 3 LASTPIN (-3275 1550) SIG_NAME M_I_CPU1_SB_CB<7>
J 0
(-3265 1560);
DISPLAY 0.659574 (-3265 1560);
PAINT MONO (-3265 1560);
DISPLAY INVISIBLE (-3265 1560);
FORCEPROP 1 LASTPIN (-3275 1550) BN 7
J 0
(-3287 1558);
DISPLAY 0.489362 (-3287 1558);
PAINT GREEN (-3287 1558);
FORCEPROP 2 LAST CDS_LIB mstr_standard
J 2
(-3225 1550);
DISPLAY 0.723404 (-3225 1550);
PAINT MONO (-3225 1550);
DISPLAY INVISIBLE (-3225 1550);
FORCEPROP 1 LAST BODY_TYPE PLUMBING
J 0
(-3225 1600);
DISPLAY 0.872340 (-3225 1600);
PAINT GREEN (-3225 1600);
DISPLAY INVISIBLE (-3225 1600);
FORCEPROP 1 LAST HDL_TAP TRUE
J 0
(-2900 1425);
DISPLAY 0.872340 (-2900 1425);
DISPLAY INVISIBLE (-2900 1425);
FORCEPROP 1 LAST PATH I242
J 0
(-3227 1550);
DISPLAY 0.872340 (-3227 1550);
PAINT GREEN (-3227 1550);
DISPLAY INVISIBLE (-3227 1550);
FORCEADD TAP..1
(-3225 1600);
FORCEPROP 3 LASTPIN (-3275 1600) SIG_NAME M_I_CPU1_SB_CB<6>
J 0
(-3265 1610);
DISPLAY 0.659574 (-3265 1610);
PAINT MONO (-3265 1610);
DISPLAY INVISIBLE (-3265 1610);
FORCEPROP 1 LASTPIN (-3275 1600) BN 6
J 0
(-3287 1608);
DISPLAY 0.489362 (-3287 1608);
PAINT GREEN (-3287 1608);
FORCEPROP 2 LAST CDS_LIB mstr_standard
J 2
(-3225 1600);
DISPLAY 0.723404 (-3225 1600);
PAINT MONO (-3225 1600);
DISPLAY INVISIBLE (-3225 1600);
FORCEPROP 1 LAST BODY_TYPE PLUMBING
J 0
(-3225 1650);
DISPLAY 0.872340 (-3225 1650);
PAINT GREEN (-3225 1650);
DISPLAY INVISIBLE (-3225 1650);
FORCEPROP 1 LAST HDL_TAP TRUE
J 0
(-2900 1475);
DISPLAY 0.872340 (-2900 1475);
DISPLAY INVISIBLE (-2900 1475);
FORCEPROP 1 LAST PATH I243
J 0
(-3227 1600);
DISPLAY 0.872340 (-3227 1600);
PAINT GREEN (-3227 1600);
DISPLAY INVISIBLE (-3227 1600);
FORCEADD TAP..1
R 2
(-5650 5950);
FORCEPROP 3 LASTPIN (-5600 5950) SIG_NAME M_I_CPU1_SA_DQS_DP<0>
J 0
(-5590 5960);
DISPLAY 0.659574 (-5590 5960);
PAINT MONO (-5590 5960);
DISPLAY INVISIBLE (-5590 5960);
FORCEPROP 1 LASTPIN (-5600 5950) BN 0
J 2
(-5588 5958);
DISPLAY 0.489362 (-5588 5958);
PAINT GREEN (-5588 5958);
FORCEPROP 2 LAST CDS_LIB mstr_standard
J 2
(-5650 5950);
DISPLAY 0.723404 (-5650 5950);
PAINT MONO (-5650 5950);
DISPLAY INVISIBLE (-5650 5950);
FORCEPROP 1 LAST BODY_TYPE PLUMBING
J 2
(-5650 6000);
DISPLAY 0.872340 (-5650 6000);
PAINT GREEN (-5650 6000);
DISPLAY INVISIBLE (-5650 6000);
FORCEPROP 1 LAST HDL_TAP TRUE
J 2
(-5975 5825);
DISPLAY 0.872340 (-5975 5825);
DISPLAY INVISIBLE (-5975 5825);
FORCEPROP 1 LAST PATH I244
J 2
(-5648 5950);
DISPLAY 0.872340 (-5648 5950);
PAINT GREEN (-5648 5950);
DISPLAY INVISIBLE (-5648 5950);
FORCEADD TAP..1
R 2
(-5650 5850);
FORCEPROP 3 LASTPIN (-5600 5850) SIG_NAME M_I_CPU1_SA_DQS_DP<1>
J 0
(-5590 5860);
DISPLAY 0.659574 (-5590 5860);
PAINT MONO (-5590 5860);
DISPLAY INVISIBLE (-5590 5860);
FORCEPROP 1 LASTPIN (-5600 5850) BN 1
J 2
(-5588 5858);
DISPLAY 0.489362 (-5588 5858);
PAINT GREEN (-5588 5858);
FORCEPROP 2 LAST CDS_LIB mstr_standard
J 2
(-5650 5850);
DISPLAY 0.723404 (-5650 5850);
PAINT MONO (-5650 5850);
DISPLAY INVISIBLE (-5650 5850);
FORCEPROP 1 LAST BODY_TYPE PLUMBING
J 2
(-5650 5900);
DISPLAY 0.872340 (-5650 5900);
PAINT GREEN (-5650 5900);
DISPLAY INVISIBLE (-5650 5900);
FORCEPROP 1 LAST HDL_TAP TRUE
J 2
(-5975 5725);
DISPLAY 0.872340 (-5975 5725);
DISPLAY INVISIBLE (-5975 5725);
FORCEPROP 1 LAST PATH I245
J 2
(-5648 5850);
DISPLAY 0.872340 (-5648 5850);
PAINT GREEN (-5648 5850);
DISPLAY INVISIBLE (-5648 5850);
FORCEADD TAP..1
R 2
(-5650 5750);
FORCEPROP 3 LASTPIN (-5600 5750) SIG_NAME M_I_CPU1_SA_DQS_DP<2>
J 0
(-5590 5760);
DISPLAY 0.659574 (-5590 5760);
PAINT MONO (-5590 5760);
DISPLAY INVISIBLE (-5590 5760);
FORCEPROP 1 LASTPIN (-5600 5750) BN 2
J 2
(-5588 5758);
DISPLAY 0.489362 (-5588 5758);
PAINT GREEN (-5588 5758);
FORCEPROP 2 LAST CDS_LIB mstr_standard
J 2
(-5650 5750);
DISPLAY 0.723404 (-5650 5750);
PAINT MONO (-5650 5750);
DISPLAY INVISIBLE (-5650 5750);
FORCEPROP 1 LAST BODY_TYPE PLUMBING
J 2
(-5650 5800);
DISPLAY 0.872340 (-5650 5800);
PAINT GREEN (-5650 5800);
DISPLAY INVISIBLE (-5650 5800);
FORCEPROP 1 LAST HDL_TAP TRUE
J 2
(-5975 5625);
DISPLAY 0.872340 (-5975 5625);
DISPLAY INVISIBLE (-5975 5625);
FORCEPROP 1 LAST PATH I246
J 2
(-5648 5750);
DISPLAY 0.872340 (-5648 5750);
PAINT GREEN (-5648 5750);
DISPLAY INVISIBLE (-5648 5750);
FORCEADD TAP..1
R 2
(-5650 5650);
FORCEPROP 3 LASTPIN (-5600 5650) SIG_NAME M_I_CPU1_SA_DQS_DP<3>
J 0
(-5590 5660);
DISPLAY 0.659574 (-5590 5660);
PAINT MONO (-5590 5660);
DISPLAY INVISIBLE (-5590 5660);
FORCEPROP 1 LASTPIN (-5600 5650) BN 3
J 2
(-5588 5658);
DISPLAY 0.489362 (-5588 5658);
PAINT GREEN (-5588 5658);
FORCEPROP 2 LAST CDS_LIB mstr_standard
J 2
(-5650 5650);
DISPLAY 0.723404 (-5650 5650);
PAINT MONO (-5650 5650);
DISPLAY INVISIBLE (-5650 5650);
FORCEPROP 1 LAST BODY_TYPE PLUMBING
J 2
(-5650 5700);
DISPLAY 0.872340 (-5650 5700);
PAINT GREEN (-5650 5700);
DISPLAY INVISIBLE (-5650 5700);
FORCEPROP 1 LAST HDL_TAP TRUE
J 2
(-5975 5525);
DISPLAY 0.872340 (-5975 5525);
DISPLAY INVISIBLE (-5975 5525);
FORCEPROP 1 LAST PATH I247
J 2
(-5648 5650);
DISPLAY 0.872340 (-5648 5650);
PAINT GREEN (-5648 5650);
DISPLAY INVISIBLE (-5648 5650);
FORCEADD TAP..1
R 2
(-5650 5450);
FORCEPROP 3 LASTPIN (-5600 5450) SIG_NAME M_I_CPU1_SA_DQS_DP<5>
J 0
(-5590 5460);
DISPLAY 0.659574 (-5590 5460);
PAINT MONO (-5590 5460);
DISPLAY INVISIBLE (-5590 5460);
FORCEPROP 1 LASTPIN (-5600 5450) BN 5
J 2
(-5588 5458);
DISPLAY 0.489362 (-5588 5458);
PAINT GREEN (-5588 5458);
FORCEPROP 2 LAST CDS_LIB mstr_standard
J 2
(-5650 5450);
DISPLAY 0.723404 (-5650 5450);
PAINT MONO (-5650 5450);
DISPLAY INVISIBLE (-5650 5450);
FORCEPROP 1 LAST BODY_TYPE PLUMBING
J 2
(-5650 5500);
DISPLAY 0.872340 (-5650 5500);
PAINT GREEN (-5650 5500);
DISPLAY INVISIBLE (-5650 5500);
FORCEPROP 1 LAST HDL_TAP TRUE
J 2
(-5975 5325);
DISPLAY 0.872340 (-5975 5325);
DISPLAY INVISIBLE (-5975 5325);
FORCEPROP 1 LAST PATH I248
J 2
(-5648 5450);
DISPLAY 0.872340 (-5648 5450);
PAINT GREEN (-5648 5450);
DISPLAY INVISIBLE (-5648 5450);
FORCEADD TAP..1
R 2
(-5650 5550);
FORCEPROP 3 LASTPIN (-5600 5550) SIG_NAME M_I_CPU1_SA_DQS_DP<4>
J 0
(-5590 5560);
DISPLAY 0.659574 (-5590 5560);
PAINT MONO (-5590 5560);
DISPLAY INVISIBLE (-5590 5560);
FORCEPROP 1 LASTPIN (-5600 5550) BN 4
J 2
(-5588 5558);
DISPLAY 0.489362 (-5588 5558);
PAINT GREEN (-5588 5558);
FORCEPROP 2 LAST CDS_LIB mstr_standard
J 2
(-5650 5550);
DISPLAY 0.723404 (-5650 5550);
PAINT MONO (-5650 5550);
DISPLAY INVISIBLE (-5650 5550);
FORCEPROP 1 LAST BODY_TYPE PLUMBING
J 2
(-5650 5600);
DISPLAY 0.872340 (-5650 5600);
PAINT GREEN (-5650 5600);
DISPLAY INVISIBLE (-5650 5600);
FORCEPROP 1 LAST HDL_TAP TRUE
J 2
(-5975 5425);
DISPLAY 0.872340 (-5975 5425);
DISPLAY INVISIBLE (-5975 5425);
FORCEPROP 1 LAST PATH I249
J 2
(-5648 5550);
DISPLAY 0.872340 (-5648 5550);
PAINT GREEN (-5648 5550);
DISPLAY INVISIBLE (-5648 5550);
FORCEADD TAP..1
R 2
(-5650 5350);
FORCEPROP 3 LASTPIN (-5600 5350) SIG_NAME M_I_CPU1_SA_DQS_DP<6>
J 0
(-5590 5360);
DISPLAY 0.659574 (-5590 5360);
PAINT MONO (-5590 5360);
DISPLAY INVISIBLE (-5590 5360);
FORCEPROP 1 LASTPIN (-5600 5350) BN 6
J 2
(-5588 5358);
DISPLAY 0.489362 (-5588 5358);
PAINT GREEN (-5588 5358);
FORCEPROP 2 LAST CDS_LIB mstr_standard
J 2
(-5650 5350);
DISPLAY 0.723404 (-5650 5350);
PAINT MONO (-5650 5350);
DISPLAY INVISIBLE (-5650 5350);
FORCEPROP 1 LAST BODY_TYPE PLUMBING
J 2
(-5650 5400);
DISPLAY 0.872340 (-5650 5400);
PAINT GREEN (-5650 5400);
DISPLAY INVISIBLE (-5650 5400);
FORCEPROP 1 LAST HDL_TAP TRUE
J 2
(-5975 5225);
DISPLAY 0.872340 (-5975 5225);
DISPLAY INVISIBLE (-5975 5225);
FORCEPROP 1 LAST PATH I250
J 2
(-5648 5350);
DISPLAY 0.872340 (-5648 5350);
PAINT GREEN (-5648 5350);
DISPLAY INVISIBLE (-5648 5350);
FORCEADD TAP..1
R 2
(-5650 5250);
FORCEPROP 3 LASTPIN (-5600 5250) SIG_NAME M_I_CPU1_SA_DQS_DP<7>
J 0
(-5590 5260);
DISPLAY 0.659574 (-5590 5260);
PAINT MONO (-5590 5260);
DISPLAY INVISIBLE (-5590 5260);
FORCEPROP 1 LASTPIN (-5600 5250) BN 7
J 2
(-5588 5258);
DISPLAY 0.489362 (-5588 5258);
PAINT GREEN (-5588 5258);
FORCEPROP 2 LAST CDS_LIB mstr_standard
J 2
(-5650 5250);
DISPLAY 0.723404 (-5650 5250);
PAINT MONO (-5650 5250);
DISPLAY INVISIBLE (-5650 5250);
FORCEPROP 1 LAST BODY_TYPE PLUMBING
J 2
(-5650 5300);
DISPLAY 0.872340 (-5650 5300);
PAINT GREEN (-5650 5300);
DISPLAY INVISIBLE (-5650 5300);
FORCEPROP 1 LAST HDL_TAP TRUE
J 2
(-5975 5125);
DISPLAY 0.872340 (-5975 5125);
DISPLAY INVISIBLE (-5975 5125);
FORCEPROP 1 LAST PATH I251
J 2
(-5648 5250);
DISPLAY 0.872340 (-5648 5250);
PAINT GREEN (-5648 5250);
DISPLAY INVISIBLE (-5648 5250);
FORCEADD TAP..1
R 2
(-5650 5150);
FORCEPROP 3 LASTPIN (-5600 5150) SIG_NAME M_I_CPU1_SA_DQS_DP<8>
J 0
(-5590 5160);
DISPLAY 0.659574 (-5590 5160);
PAINT MONO (-5590 5160);
DISPLAY INVISIBLE (-5590 5160);
FORCEPROP 1 LASTPIN (-5600 5150) BN 8
J 2
(-5588 5158);
DISPLAY 0.489362 (-5588 5158);
PAINT GREEN (-5588 5158);
FORCEPROP 2 LAST CDS_LIB mstr_standard
J 2
(-5650 5150);
DISPLAY 0.723404 (-5650 5150);
PAINT MONO (-5650 5150);
DISPLAY INVISIBLE (-5650 5150);
FORCEPROP 1 LAST BODY_TYPE PLUMBING
J 2
(-5650 5200);
DISPLAY 0.872340 (-5650 5200);
PAINT GREEN (-5650 5200);
DISPLAY INVISIBLE (-5650 5200);
FORCEPROP 1 LAST HDL_TAP TRUE
J 2
(-5975 5025);
DISPLAY 0.872340 (-5975 5025);
DISPLAY INVISIBLE (-5975 5025);
FORCEPROP 1 LAST PATH I252
J 2
(-5648 5150);
DISPLAY 0.872340 (-5648 5150);
PAINT GREEN (-5648 5150);
DISPLAY INVISIBLE (-5648 5150);
FORCEADD TAP..1
R 2
(-5850 5900);
FORCEPROP 3 LASTPIN (-5800 5900) SIG_NAME M_I_CPU1_SA_DQS_DN<0>
J 0
(-5790 5910);
DISPLAY 0.659574 (-5790 5910);
PAINT MONO (-5790 5910);
DISPLAY INVISIBLE (-5790 5910);
FORCEPROP 1 LASTPIN (-5800 5900) BN 0
J 2
(-5788 5908);
DISPLAY 0.489362 (-5788 5908);
PAINT GREEN (-5788 5908);
FORCEPROP 2 LAST CDS_LIB mstr_standard
J 2
(-5850 5900);
DISPLAY 0.723404 (-5850 5900);
PAINT MONO (-5850 5900);
DISPLAY INVISIBLE (-5850 5900);
FORCEPROP 1 LAST BODY_TYPE PLUMBING
J 2
(-5850 5950);
DISPLAY 0.872340 (-5850 5950);
PAINT GREEN (-5850 5950);
DISPLAY INVISIBLE (-5850 5950);
FORCEPROP 1 LAST HDL_TAP TRUE
J 2
(-6175 5775);
DISPLAY 0.872340 (-6175 5775);
DISPLAY INVISIBLE (-6175 5775);
FORCEPROP 1 LAST PATH I253
J 2
(-5848 5900);
DISPLAY 0.872340 (-5848 5900);
PAINT GREEN (-5848 5900);
DISPLAY INVISIBLE (-5848 5900);
FORCEADD TAP..1
R 2
(-5850 5700);
FORCEPROP 3 LASTPIN (-5800 5700) SIG_NAME M_I_CPU1_SA_DQS_DN<2>
J 0
(-5790 5710);
DISPLAY 0.659574 (-5790 5710);
PAINT MONO (-5790 5710);
DISPLAY INVISIBLE (-5790 5710);
FORCEPROP 1 LASTPIN (-5800 5700) BN 2
J 2
(-5788 5708);
DISPLAY 0.489362 (-5788 5708);
PAINT GREEN (-5788 5708);
FORCEPROP 2 LAST CDS_LIB mstr_standard
J 2
(-5850 5700);
DISPLAY 0.723404 (-5850 5700);
PAINT MONO (-5850 5700);
DISPLAY INVISIBLE (-5850 5700);
FORCEPROP 1 LAST BODY_TYPE PLUMBING
J 2
(-5850 5750);
DISPLAY 0.872340 (-5850 5750);
PAINT GREEN (-5850 5750);
DISPLAY INVISIBLE (-5850 5750);
FORCEPROP 1 LAST HDL_TAP TRUE
J 2
(-6175 5575);
DISPLAY 0.872340 (-6175 5575);
DISPLAY INVISIBLE (-6175 5575);
FORCEPROP 1 LAST PATH I254
J 2
(-5848 5700);
DISPLAY 0.872340 (-5848 5700);
PAINT GREEN (-5848 5700);
DISPLAY INVISIBLE (-5848 5700);
FORCEADD TAP..1
R 2
(-5850 5800);
FORCEPROP 3 LASTPIN (-5800 5800) SIG_NAME M_I_CPU1_SA_DQS_DN<1>
J 0
(-5790 5810);
DISPLAY 0.659574 (-5790 5810);
PAINT MONO (-5790 5810);
DISPLAY INVISIBLE (-5790 5810);
FORCEPROP 1 LASTPIN (-5800 5800) BN 1
J 2
(-5788 5808);
DISPLAY 0.489362 (-5788 5808);
PAINT GREEN (-5788 5808);
FORCEPROP 2 LAST CDS_LIB mstr_standard
J 2
(-5850 5800);
DISPLAY 0.723404 (-5850 5800);
PAINT MONO (-5850 5800);
DISPLAY INVISIBLE (-5850 5800);
FORCEPROP 1 LAST BODY_TYPE PLUMBING
J 2
(-5850 5850);
DISPLAY 0.872340 (-5850 5850);
PAINT GREEN (-5850 5850);
DISPLAY INVISIBLE (-5850 5850);
FORCEPROP 1 LAST HDL_TAP TRUE
J 2
(-6175 5675);
DISPLAY 0.872340 (-6175 5675);
DISPLAY INVISIBLE (-6175 5675);
FORCEPROP 1 LAST PATH I255
J 2
(-5848 5800);
DISPLAY 0.872340 (-5848 5800);
PAINT GREEN (-5848 5800);
DISPLAY INVISIBLE (-5848 5800);
FORCEADD TAP..1
R 2
(-5850 5400);
FORCEPROP 3 LASTPIN (-5800 5400) SIG_NAME M_I_CPU1_SA_DQS_DN<5>
J 0
(-5790 5410);
DISPLAY 0.659574 (-5790 5410);
PAINT MONO (-5790 5410);
DISPLAY INVISIBLE (-5790 5410);
FORCEPROP 1 LASTPIN (-5800 5400) BN 5
J 2
(-5788 5408);
DISPLAY 0.489362 (-5788 5408);
PAINT GREEN (-5788 5408);
FORCEPROP 2 LAST CDS_LIB mstr_standard
J 2
(-5850 5400);
DISPLAY 0.723404 (-5850 5400);
PAINT MONO (-5850 5400);
DISPLAY INVISIBLE (-5850 5400);
FORCEPROP 1 LAST BODY_TYPE PLUMBING
J 2
(-5850 5450);
DISPLAY 0.872340 (-5850 5450);
PAINT GREEN (-5850 5450);
DISPLAY INVISIBLE (-5850 5450);
FORCEPROP 1 LAST HDL_TAP TRUE
J 2
(-6175 5275);
DISPLAY 0.872340 (-6175 5275);
DISPLAY INVISIBLE (-6175 5275);
FORCEPROP 1 LAST PATH I256
J 2
(-5848 5400);
DISPLAY 0.872340 (-5848 5400);
PAINT GREEN (-5848 5400);
DISPLAY INVISIBLE (-5848 5400);
FORCEADD TAP..1
R 2
(-5850 5600);
FORCEPROP 3 LASTPIN (-5800 5600) SIG_NAME M_I_CPU1_SA_DQS_DN<3>
J 0
(-5790 5610);
DISPLAY 0.659574 (-5790 5610);
PAINT MONO (-5790 5610);
DISPLAY INVISIBLE (-5790 5610);
FORCEPROP 1 LASTPIN (-5800 5600) BN 3
J 2
(-5788 5608);
DISPLAY 0.489362 (-5788 5608);
PAINT GREEN (-5788 5608);
FORCEPROP 2 LAST CDS_LIB mstr_standard
J 2
(-5850 5600);
DISPLAY 0.723404 (-5850 5600);
PAINT MONO (-5850 5600);
DISPLAY INVISIBLE (-5850 5600);
FORCEPROP 1 LAST BODY_TYPE PLUMBING
J 2
(-5850 5650);
DISPLAY 0.872340 (-5850 5650);
PAINT GREEN (-5850 5650);
DISPLAY INVISIBLE (-5850 5650);
FORCEPROP 1 LAST HDL_TAP TRUE
J 2
(-6175 5475);
DISPLAY 0.872340 (-6175 5475);
DISPLAY INVISIBLE (-6175 5475);
FORCEPROP 1 LAST PATH I257
J 2
(-5848 5600);
DISPLAY 0.872340 (-5848 5600);
PAINT GREEN (-5848 5600);
DISPLAY INVISIBLE (-5848 5600);
FORCEADD TAP..1
R 2
(-5850 5500);
FORCEPROP 3 LASTPIN (-5800 5500) SIG_NAME M_I_CPU1_SA_DQS_DN<4>
J 0
(-5790 5510);
DISPLAY 0.659574 (-5790 5510);
PAINT MONO (-5790 5510);
DISPLAY INVISIBLE (-5790 5510);
FORCEPROP 1 LASTPIN (-5800 5500) BN 4
J 2
(-5788 5508);
DISPLAY 0.489362 (-5788 5508);
PAINT GREEN (-5788 5508);
FORCEPROP 2 LAST CDS_LIB mstr_standard
J 2
(-5850 5500);
DISPLAY 0.723404 (-5850 5500);
PAINT MONO (-5850 5500);
DISPLAY INVISIBLE (-5850 5500);
FORCEPROP 1 LAST BODY_TYPE PLUMBING
J 2
(-5850 5550);
DISPLAY 0.872340 (-5850 5550);
PAINT GREEN (-5850 5550);
DISPLAY INVISIBLE (-5850 5550);
FORCEPROP 1 LAST HDL_TAP TRUE
J 2
(-6175 5375);
DISPLAY 0.872340 (-6175 5375);
DISPLAY INVISIBLE (-6175 5375);
FORCEPROP 1 LAST PATH I258
J 2
(-5848 5500);
DISPLAY 0.872340 (-5848 5500);
PAINT GREEN (-5848 5500);
DISPLAY INVISIBLE (-5848 5500);
FORCEADD TAP..1
R 2
(-5850 5200);
FORCEPROP 3 LASTPIN (-5800 5200) SIG_NAME M_I_CPU1_SA_DQS_DN<7>
J 0
(-5790 5210);
DISPLAY 0.659574 (-5790 5210);
PAINT MONO (-5790 5210);
DISPLAY INVISIBLE (-5790 5210);
FORCEPROP 1 LASTPIN (-5800 5200) BN 7
J 2
(-5788 5208);
DISPLAY 0.489362 (-5788 5208);
PAINT GREEN (-5788 5208);
FORCEPROP 2 LAST CDS_LIB mstr_standard
J 2
(-5850 5200);
DISPLAY 0.723404 (-5850 5200);
PAINT MONO (-5850 5200);
DISPLAY INVISIBLE (-5850 5200);
FORCEPROP 1 LAST BODY_TYPE PLUMBING
J 2
(-5850 5250);
DISPLAY 0.872340 (-5850 5250);
PAINT GREEN (-5850 5250);
DISPLAY INVISIBLE (-5850 5250);
FORCEPROP 1 LAST HDL_TAP TRUE
J 2
(-6175 5075);
DISPLAY 0.872340 (-6175 5075);
DISPLAY INVISIBLE (-6175 5075);
FORCEPROP 1 LAST PATH I259
J 2
(-5848 5200);
DISPLAY 0.872340 (-5848 5200);
PAINT GREEN (-5848 5200);
DISPLAY INVISIBLE (-5848 5200);
FORCEADD TAP..1
R 2
(-5850 5300);
FORCEPROP 3 LASTPIN (-5800 5300) SIG_NAME M_I_CPU1_SA_DQS_DN<6>
J 0
(-5790 5310);
DISPLAY 0.659574 (-5790 5310);
PAINT MONO (-5790 5310);
DISPLAY INVISIBLE (-5790 5310);
FORCEPROP 1 LASTPIN (-5800 5300) BN 6
J 2
(-5788 5308);
DISPLAY 0.489362 (-5788 5308);
PAINT GREEN (-5788 5308);
FORCEPROP 2 LAST CDS_LIB mstr_standard
J 2
(-5850 5300);
DISPLAY 0.723404 (-5850 5300);
PAINT MONO (-5850 5300);
DISPLAY INVISIBLE (-5850 5300);
FORCEPROP 1 LAST BODY_TYPE PLUMBING
J 2
(-5850 5350);
DISPLAY 0.872340 (-5850 5350);
PAINT GREEN (-5850 5350);
DISPLAY INVISIBLE (-5850 5350);
FORCEPROP 1 LAST HDL_TAP TRUE
J 2
(-6175 5175);
DISPLAY 0.872340 (-6175 5175);
DISPLAY INVISIBLE (-6175 5175);
FORCEPROP 1 LAST PATH I260
J 2
(-5848 5300);
DISPLAY 0.872340 (-5848 5300);
PAINT GREEN (-5848 5300);
DISPLAY INVISIBLE (-5848 5300);
FORCEADD TAP..1
R 2
(-5650 4900);
FORCEPROP 3 LASTPIN (-5600 4900) SIG_NAME M_I_CPU1_SB_DQS_DP<0>
J 0
(-5590 4910);
DISPLAY 0.659574 (-5590 4910);
PAINT MONO (-5590 4910);
DISPLAY INVISIBLE (-5590 4910);
FORCEPROP 1 LASTPIN (-5600 4900) BN 0
J 2
(-5588 4908);
DISPLAY 0.489362 (-5588 4908);
PAINT GREEN (-5588 4908);
FORCEPROP 2 LAST CDS_LIB mstr_standard
J 2
(-5650 4900);
DISPLAY 0.723404 (-5650 4900);
PAINT MONO (-5650 4900);
DISPLAY INVISIBLE (-5650 4900);
FORCEPROP 1 LAST BODY_TYPE PLUMBING
J 2
(-5650 4950);
DISPLAY 0.872340 (-5650 4950);
PAINT GREEN (-5650 4950);
DISPLAY INVISIBLE (-5650 4950);
FORCEPROP 1 LAST HDL_TAP TRUE
J 2
(-5975 4775);
DISPLAY 0.872340 (-5975 4775);
DISPLAY INVISIBLE (-5975 4775);
FORCEPROP 1 LAST PATH I261
J 2
(-5648 4900);
DISPLAY 0.872340 (-5648 4900);
PAINT GREEN (-5648 4900);
DISPLAY INVISIBLE (-5648 4900);
FORCEADD TAP..1
R 2
(-5650 5050);
FORCEPROP 3 LASTPIN (-5600 5050) SIG_NAME M_I_CPU1_SA_DQS_DP<9>
J 0
(-5590 5060);
DISPLAY 0.659574 (-5590 5060);
PAINT MONO (-5590 5060);
DISPLAY INVISIBLE (-5590 5060);
FORCEPROP 1 LASTPIN (-5600 5050) BN 9
J 2
(-5588 5058);
DISPLAY 0.489362 (-5588 5058);
PAINT GREEN (-5588 5058);
FORCEPROP 2 LAST CDS_LIB mstr_standard
J 2
(-5650 5050);
DISPLAY 0.723404 (-5650 5050);
PAINT MONO (-5650 5050);
DISPLAY INVISIBLE (-5650 5050);
FORCEPROP 1 LAST BODY_TYPE PLUMBING
J 2
(-5650 5100);
DISPLAY 0.872340 (-5650 5100);
PAINT GREEN (-5650 5100);
DISPLAY INVISIBLE (-5650 5100);
FORCEPROP 1 LAST HDL_TAP TRUE
J 2
(-5975 4925);
DISPLAY 0.872340 (-5975 4925);
DISPLAY INVISIBLE (-5975 4925);
FORCEPROP 1 LAST PATH I262
J 2
(-5648 5050);
DISPLAY 0.872340 (-5648 5050);
PAINT GREEN (-5648 5050);
DISPLAY INVISIBLE (-5648 5050);
FORCEADD TAP..1
R 2
(-5650 4800);
FORCEPROP 3 LASTPIN (-5600 4800) SIG_NAME M_I_CPU1_SB_DQS_DP<1>
J 0
(-5590 4810);
DISPLAY 0.659574 (-5590 4810);
PAINT MONO (-5590 4810);
DISPLAY INVISIBLE (-5590 4810);
FORCEPROP 1 LASTPIN (-5600 4800) BN 1
J 2
(-5588 4808);
DISPLAY 0.489362 (-5588 4808);
PAINT GREEN (-5588 4808);
FORCEPROP 2 LAST CDS_LIB mstr_standard
J 2
(-5650 4800);
DISPLAY 0.723404 (-5650 4800);
PAINT MONO (-5650 4800);
DISPLAY INVISIBLE (-5650 4800);
FORCEPROP 1 LAST BODY_TYPE PLUMBING
J 2
(-5650 4850);
DISPLAY 0.872340 (-5650 4850);
PAINT GREEN (-5650 4850);
DISPLAY INVISIBLE (-5650 4850);
FORCEPROP 1 LAST HDL_TAP TRUE
J 2
(-5975 4675);
DISPLAY 0.872340 (-5975 4675);
DISPLAY INVISIBLE (-5975 4675);
FORCEPROP 1 LAST PATH I263
J 2
(-5648 4800);
DISPLAY 0.872340 (-5648 4800);
PAINT GREEN (-5648 4800);
DISPLAY INVISIBLE (-5648 4800);
FORCEADD TAP..1
R 2
(-5650 4700);
FORCEPROP 3 LASTPIN (-5600 4700) SIG_NAME M_I_CPU1_SB_DQS_DP<2>
J 0
(-5590 4710);
DISPLAY 0.659574 (-5590 4710);
PAINT MONO (-5590 4710);
DISPLAY INVISIBLE (-5590 4710);
FORCEPROP 1 LASTPIN (-5600 4700) BN 2
J 2
(-5588 4708);
DISPLAY 0.489362 (-5588 4708);
PAINT GREEN (-5588 4708);
FORCEPROP 2 LAST CDS_LIB mstr_standard
J 2
(-5650 4700);
DISPLAY 0.723404 (-5650 4700);
PAINT MONO (-5650 4700);
DISPLAY INVISIBLE (-5650 4700);
FORCEPROP 1 LAST BODY_TYPE PLUMBING
J 2
(-5650 4750);
DISPLAY 0.872340 (-5650 4750);
PAINT GREEN (-5650 4750);
DISPLAY INVISIBLE (-5650 4750);
FORCEPROP 1 LAST HDL_TAP TRUE
J 2
(-5975 4575);
DISPLAY 0.872340 (-5975 4575);
DISPLAY INVISIBLE (-5975 4575);
FORCEPROP 1 LAST PATH I264
J 2
(-5648 4700);
DISPLAY 0.872340 (-5648 4700);
PAINT GREEN (-5648 4700);
DISPLAY INVISIBLE (-5648 4700);
FORCEADD TAP..1
R 2
(-5650 4400);
FORCEPROP 3 LASTPIN (-5600 4400) SIG_NAME M_I_CPU1_SB_DQS_DP<5>
J 0
(-5590 4410);
DISPLAY 0.659574 (-5590 4410);
PAINT MONO (-5590 4410);
DISPLAY INVISIBLE (-5590 4410);
FORCEPROP 1 LASTPIN (-5600 4400) BN 5
J 2
(-5588 4408);
DISPLAY 0.489362 (-5588 4408);
PAINT GREEN (-5588 4408);
FORCEPROP 2 LAST CDS_LIB mstr_standard
J 2
(-5650 4400);
DISPLAY 0.723404 (-5650 4400);
PAINT MONO (-5650 4400);
DISPLAY INVISIBLE (-5650 4400);
FORCEPROP 1 LAST BODY_TYPE PLUMBING
J 2
(-5650 4450);
DISPLAY 0.872340 (-5650 4450);
PAINT GREEN (-5650 4450);
DISPLAY INVISIBLE (-5650 4450);
FORCEPROP 1 LAST HDL_TAP TRUE
J 2
(-5975 4275);
DISPLAY 0.872340 (-5975 4275);
DISPLAY INVISIBLE (-5975 4275);
FORCEPROP 1 LAST PATH I265
J 2
(-5648 4400);
DISPLAY 0.872340 (-5648 4400);
PAINT GREEN (-5648 4400);
DISPLAY INVISIBLE (-5648 4400);
FORCEADD TAP..1
R 2
(-5650 4600);
FORCEPROP 3 LASTPIN (-5600 4600) SIG_NAME M_I_CPU1_SB_DQS_DP<3>
J 0
(-5590 4610);
DISPLAY 0.659574 (-5590 4610);
PAINT MONO (-5590 4610);
DISPLAY INVISIBLE (-5590 4610);
FORCEPROP 1 LASTPIN (-5600 4600) BN 3
J 2
(-5588 4608);
DISPLAY 0.489362 (-5588 4608);
PAINT GREEN (-5588 4608);
FORCEPROP 2 LAST CDS_LIB mstr_standard
J 2
(-5650 4600);
DISPLAY 0.723404 (-5650 4600);
PAINT MONO (-5650 4600);
DISPLAY INVISIBLE (-5650 4600);
FORCEPROP 1 LAST BODY_TYPE PLUMBING
J 2
(-5650 4650);
DISPLAY 0.872340 (-5650 4650);
PAINT GREEN (-5650 4650);
DISPLAY INVISIBLE (-5650 4650);
FORCEPROP 1 LAST HDL_TAP TRUE
J 2
(-5975 4475);
DISPLAY 0.872340 (-5975 4475);
DISPLAY INVISIBLE (-5975 4475);
FORCEPROP 1 LAST PATH I266
J 2
(-5648 4600);
DISPLAY 0.872340 (-5648 4600);
PAINT GREEN (-5648 4600);
DISPLAY INVISIBLE (-5648 4600);
FORCEADD TAP..1
R 2
(-5650 4500);
FORCEPROP 3 LASTPIN (-5600 4500) SIG_NAME M_I_CPU1_SB_DQS_DP<4>
J 0
(-5590 4510);
DISPLAY 0.659574 (-5590 4510);
PAINT MONO (-5590 4510);
DISPLAY INVISIBLE (-5590 4510);
FORCEPROP 1 LASTPIN (-5600 4500) BN 4
J 2
(-5588 4508);
DISPLAY 0.489362 (-5588 4508);
PAINT GREEN (-5588 4508);
FORCEPROP 2 LAST CDS_LIB mstr_standard
J 2
(-5650 4500);
DISPLAY 0.723404 (-5650 4500);
PAINT MONO (-5650 4500);
DISPLAY INVISIBLE (-5650 4500);
FORCEPROP 1 LAST BODY_TYPE PLUMBING
J 2
(-5650 4550);
DISPLAY 0.872340 (-5650 4550);
PAINT GREEN (-5650 4550);
DISPLAY INVISIBLE (-5650 4550);
FORCEPROP 1 LAST HDL_TAP TRUE
J 2
(-5975 4375);
DISPLAY 0.872340 (-5975 4375);
DISPLAY INVISIBLE (-5975 4375);
FORCEPROP 1 LAST PATH I267
J 2
(-5648 4500);
DISPLAY 0.872340 (-5648 4500);
PAINT GREEN (-5648 4500);
DISPLAY INVISIBLE (-5648 4500);
FORCEADD TAP..1
R 2
(-5650 4300);
FORCEPROP 3 LASTPIN (-5600 4300) SIG_NAME M_I_CPU1_SB_DQS_DP<6>
J 0
(-5590 4310);
DISPLAY 0.659574 (-5590 4310);
PAINT MONO (-5590 4310);
DISPLAY INVISIBLE (-5590 4310);
FORCEPROP 1 LASTPIN (-5600 4300) BN 6
J 2
(-5588 4308);
DISPLAY 0.489362 (-5588 4308);
PAINT GREEN (-5588 4308);
FORCEPROP 2 LAST CDS_LIB mstr_standard
J 2
(-5650 4300);
DISPLAY 0.723404 (-5650 4300);
PAINT MONO (-5650 4300);
DISPLAY INVISIBLE (-5650 4300);
FORCEPROP 1 LAST BODY_TYPE PLUMBING
J 2
(-5650 4350);
DISPLAY 0.872340 (-5650 4350);
PAINT GREEN (-5650 4350);
DISPLAY INVISIBLE (-5650 4350);
FORCEPROP 1 LAST HDL_TAP TRUE
J 2
(-5975 4175);
DISPLAY 0.872340 (-5975 4175);
DISPLAY INVISIBLE (-5975 4175);
FORCEPROP 1 LAST PATH I268
J 2
(-5648 4300);
DISPLAY 0.872340 (-5648 4300);
PAINT GREEN (-5648 4300);
DISPLAY INVISIBLE (-5648 4300);
FORCEADD TAP..1
R 2
(-5650 4200);
FORCEPROP 3 LASTPIN (-5600 4200) SIG_NAME M_I_CPU1_SB_DQS_DP<7>
J 0
(-5590 4210);
DISPLAY 0.659574 (-5590 4210);
PAINT MONO (-5590 4210);
DISPLAY INVISIBLE (-5590 4210);
FORCEPROP 1 LASTPIN (-5600 4200) BN 7
J 2
(-5588 4208);
DISPLAY 0.489362 (-5588 4208);
PAINT GREEN (-5588 4208);
FORCEPROP 2 LAST CDS_LIB mstr_standard
J 2
(-5650 4200);
DISPLAY 0.723404 (-5650 4200);
PAINT MONO (-5650 4200);
DISPLAY INVISIBLE (-5650 4200);
FORCEPROP 1 LAST BODY_TYPE PLUMBING
J 2
(-5650 4250);
DISPLAY 0.872340 (-5650 4250);
PAINT GREEN (-5650 4250);
DISPLAY INVISIBLE (-5650 4250);
FORCEPROP 1 LAST HDL_TAP TRUE
J 2
(-5975 4075);
DISPLAY 0.872340 (-5975 4075);
DISPLAY INVISIBLE (-5975 4075);
FORCEPROP 1 LAST PATH I269
J 2
(-5648 4200);
DISPLAY 0.872340 (-5648 4200);
PAINT GREEN (-5648 4200);
DISPLAY INVISIBLE (-5648 4200);
FORCEADD TAP..1
R 2
(-5650 4100);
FORCEPROP 3 LASTPIN (-5600 4100) SIG_NAME M_I_CPU1_SB_DQS_DP<8>
J 0
(-5590 4110);
DISPLAY 0.659574 (-5590 4110);
PAINT MONO (-5590 4110);
DISPLAY INVISIBLE (-5590 4110);
FORCEPROP 1 LASTPIN (-5600 4100) BN 8
J 2
(-5588 4108);
DISPLAY 0.489362 (-5588 4108);
PAINT GREEN (-5588 4108);
FORCEPROP 2 LAST CDS_LIB mstr_standard
J 2
(-5650 4100);
DISPLAY 0.723404 (-5650 4100);
PAINT MONO (-5650 4100);
DISPLAY INVISIBLE (-5650 4100);
FORCEPROP 1 LAST BODY_TYPE PLUMBING
J 2
(-5650 4150);
DISPLAY 0.872340 (-5650 4150);
PAINT GREEN (-5650 4150);
DISPLAY INVISIBLE (-5650 4150);
FORCEPROP 1 LAST HDL_TAP TRUE
J 2
(-5975 3975);
DISPLAY 0.872340 (-5975 3975);
DISPLAY INVISIBLE (-5975 3975);
FORCEPROP 1 LAST PATH I270
J 2
(-5648 4100);
DISPLAY 0.872340 (-5648 4100);
PAINT GREEN (-5648 4100);
DISPLAY INVISIBLE (-5648 4100);
FORCEADD TAP..1
R 2
(-5850 5100);
FORCEPROP 3 LASTPIN (-5800 5100) SIG_NAME M_I_CPU1_SA_DQS_DN<8>
J 0
(-5790 5110);
DISPLAY 0.659574 (-5790 5110);
PAINT MONO (-5790 5110);
DISPLAY INVISIBLE (-5790 5110);
FORCEPROP 1 LASTPIN (-5800 5100) BN 8
J 2
(-5788 5108);
DISPLAY 0.489362 (-5788 5108);
PAINT GREEN (-5788 5108);
FORCEPROP 2 LAST CDS_LIB mstr_standard
J 2
(-5850 5100);
DISPLAY 0.723404 (-5850 5100);
PAINT MONO (-5850 5100);
DISPLAY INVISIBLE (-5850 5100);
FORCEPROP 1 LAST BODY_TYPE PLUMBING
J 2
(-5850 5150);
DISPLAY 0.872340 (-5850 5150);
PAINT GREEN (-5850 5150);
DISPLAY INVISIBLE (-5850 5150);
FORCEPROP 1 LAST HDL_TAP TRUE
J 2
(-6175 4975);
DISPLAY 0.872340 (-6175 4975);
DISPLAY INVISIBLE (-6175 4975);
FORCEPROP 1 LAST PATH I271
J 2
(-5848 5100);
DISPLAY 0.872340 (-5848 5100);
PAINT GREEN (-5848 5100);
DISPLAY INVISIBLE (-5848 5100);
FORCEADD TAP..1
R 2
(-5850 5000);
FORCEPROP 3 LASTPIN (-5800 5000) SIG_NAME M_I_CPU1_SA_DQS_DN<9>
J 0
(-5790 5010);
DISPLAY 0.659574 (-5790 5010);
PAINT MONO (-5790 5010);
DISPLAY INVISIBLE (-5790 5010);
FORCEPROP 1 LASTPIN (-5800 5000) BN 9
J 2
(-5788 5008);
DISPLAY 0.489362 (-5788 5008);
PAINT GREEN (-5788 5008);
FORCEPROP 2 LAST CDS_LIB mstr_standard
J 2
(-5850 5000);
DISPLAY 0.723404 (-5850 5000);
PAINT MONO (-5850 5000);
DISPLAY INVISIBLE (-5850 5000);
FORCEPROP 1 LAST BODY_TYPE PLUMBING
J 2
(-5850 5050);
DISPLAY 0.872340 (-5850 5050);
PAINT GREEN (-5850 5050);
DISPLAY INVISIBLE (-5850 5050);
FORCEPROP 1 LAST HDL_TAP TRUE
J 2
(-6175 4875);
DISPLAY 0.872340 (-6175 4875);
DISPLAY INVISIBLE (-6175 4875);
FORCEPROP 1 LAST PATH I272
J 2
(-5848 5000);
DISPLAY 0.872340 (-5848 5000);
PAINT GREEN (-5848 5000);
DISPLAY INVISIBLE (-5848 5000);
FORCEADD TAP..1
R 2
(-5850 4850);
FORCEPROP 3 LASTPIN (-5800 4850) SIG_NAME M_I_CPU1_SB_DQS_DN<0>
J 0
(-5790 4860);
DISPLAY 0.659574 (-5790 4860);
PAINT MONO (-5790 4860);
DISPLAY INVISIBLE (-5790 4860);
FORCEPROP 1 LASTPIN (-5800 4850) BN 0
J 2
(-5788 4858);
DISPLAY 0.489362 (-5788 4858);
PAINT GREEN (-5788 4858);
FORCEPROP 2 LAST CDS_LIB mstr_standard
J 2
(-5850 4850);
DISPLAY 0.723404 (-5850 4850);
PAINT MONO (-5850 4850);
DISPLAY INVISIBLE (-5850 4850);
FORCEPROP 1 LAST BODY_TYPE PLUMBING
J 2
(-5850 4900);
DISPLAY 0.872340 (-5850 4900);
PAINT GREEN (-5850 4900);
DISPLAY INVISIBLE (-5850 4900);
FORCEPROP 1 LAST HDL_TAP TRUE
J 2
(-6175 4725);
DISPLAY 0.872340 (-6175 4725);
DISPLAY INVISIBLE (-6175 4725);
FORCEPROP 1 LAST PATH I273
J 2
(-5848 4850);
DISPLAY 0.872340 (-5848 4850);
PAINT GREEN (-5848 4850);
DISPLAY INVISIBLE (-5848 4850);
FORCEADD TAP..1
R 2
(-5850 4650);
FORCEPROP 3 LASTPIN (-5800 4650) SIG_NAME M_I_CPU1_SB_DQS_DN<2>
J 0
(-5790 4660);
DISPLAY 0.659574 (-5790 4660);
PAINT MONO (-5790 4660);
DISPLAY INVISIBLE (-5790 4660);
FORCEPROP 1 LASTPIN (-5800 4650) BN 2
J 2
(-5788 4658);
DISPLAY 0.489362 (-5788 4658);
PAINT GREEN (-5788 4658);
FORCEPROP 2 LAST CDS_LIB mstr_standard
J 2
(-5850 4650);
DISPLAY 0.723404 (-5850 4650);
PAINT MONO (-5850 4650);
DISPLAY INVISIBLE (-5850 4650);
FORCEPROP 1 LAST BODY_TYPE PLUMBING
J 2
(-5850 4700);
DISPLAY 0.872340 (-5850 4700);
PAINT GREEN (-5850 4700);
DISPLAY INVISIBLE (-5850 4700);
FORCEPROP 1 LAST HDL_TAP TRUE
J 2
(-6175 4525);
DISPLAY 0.872340 (-6175 4525);
DISPLAY INVISIBLE (-6175 4525);
FORCEPROP 1 LAST PATH I274
J 2
(-5848 4650);
DISPLAY 0.872340 (-5848 4650);
PAINT GREEN (-5848 4650);
DISPLAY INVISIBLE (-5848 4650);
FORCEADD TAP..1
R 2
(-5850 4750);
FORCEPROP 3 LASTPIN (-5800 4750) SIG_NAME M_I_CPU1_SB_DQS_DN<1>
J 0
(-5790 4760);
DISPLAY 0.659574 (-5790 4760);
PAINT MONO (-5790 4760);
DISPLAY INVISIBLE (-5790 4760);
FORCEPROP 1 LASTPIN (-5800 4750) BN 1
J 2
(-5788 4758);
DISPLAY 0.489362 (-5788 4758);
PAINT GREEN (-5788 4758);
FORCEPROP 2 LAST CDS_LIB mstr_standard
J 2
(-5850 4750);
DISPLAY 0.723404 (-5850 4750);
PAINT MONO (-5850 4750);
DISPLAY INVISIBLE (-5850 4750);
FORCEPROP 1 LAST BODY_TYPE PLUMBING
J 2
(-5850 4800);
DISPLAY 0.872340 (-5850 4800);
PAINT GREEN (-5850 4800);
DISPLAY INVISIBLE (-5850 4800);
FORCEPROP 1 LAST HDL_TAP TRUE
J 2
(-6175 4625);
DISPLAY 0.872340 (-6175 4625);
DISPLAY INVISIBLE (-6175 4625);
FORCEPROP 1 LAST PATH I275
J 2
(-5848 4750);
DISPLAY 0.872340 (-5848 4750);
PAINT GREEN (-5848 4750);
DISPLAY INVISIBLE (-5848 4750);
FORCEADD TAP..1
R 2
(-5850 4450);
FORCEPROP 3 LASTPIN (-5800 4450) SIG_NAME M_I_CPU1_SB_DQS_DN<4>
J 0
(-5790 4460);
DISPLAY 0.659574 (-5790 4460);
PAINT MONO (-5790 4460);
DISPLAY INVISIBLE (-5790 4460);
FORCEPROP 1 LASTPIN (-5800 4450) BN 4
J 2
(-5788 4458);
DISPLAY 0.489362 (-5788 4458);
PAINT GREEN (-5788 4458);
FORCEPROP 2 LAST CDS_LIB mstr_standard
J 2
(-5850 4450);
DISPLAY 0.723404 (-5850 4450);
PAINT MONO (-5850 4450);
DISPLAY INVISIBLE (-5850 4450);
FORCEPROP 1 LAST BODY_TYPE PLUMBING
J 2
(-5850 4500);
DISPLAY 0.872340 (-5850 4500);
PAINT GREEN (-5850 4500);
DISPLAY INVISIBLE (-5850 4500);
FORCEPROP 1 LAST HDL_TAP TRUE
J 2
(-6175 4325);
DISPLAY 0.872340 (-6175 4325);
DISPLAY INVISIBLE (-6175 4325);
FORCEPROP 1 LAST PATH I276
J 2
(-5848 4450);
DISPLAY 0.872340 (-5848 4450);
PAINT GREEN (-5848 4450);
DISPLAY INVISIBLE (-5848 4450);
FORCEADD TAP..1
R 2
(-5850 4550);
FORCEPROP 3 LASTPIN (-5800 4550) SIG_NAME M_I_CPU1_SB_DQS_DN<3>
J 0
(-5790 4560);
DISPLAY 0.659574 (-5790 4560);
PAINT MONO (-5790 4560);
DISPLAY INVISIBLE (-5790 4560);
FORCEPROP 1 LASTPIN (-5800 4550) BN 3
J 2
(-5788 4558);
DISPLAY 0.489362 (-5788 4558);
PAINT GREEN (-5788 4558);
FORCEPROP 2 LAST CDS_LIB mstr_standard
J 2
(-5850 4550);
DISPLAY 0.723404 (-5850 4550);
PAINT MONO (-5850 4550);
DISPLAY INVISIBLE (-5850 4550);
FORCEPROP 1 LAST BODY_TYPE PLUMBING
J 2
(-5850 4600);
DISPLAY 0.872340 (-5850 4600);
PAINT GREEN (-5850 4600);
DISPLAY INVISIBLE (-5850 4600);
FORCEPROP 1 LAST HDL_TAP TRUE
J 2
(-6175 4425);
DISPLAY 0.872340 (-6175 4425);
DISPLAY INVISIBLE (-6175 4425);
FORCEPROP 1 LAST PATH I277
J 2
(-5848 4550);
DISPLAY 0.872340 (-5848 4550);
PAINT GREEN (-5848 4550);
DISPLAY INVISIBLE (-5848 4550);
FORCEADD TAP..1
R 2
(-5850 4350);
FORCEPROP 3 LASTPIN (-5800 4350) SIG_NAME M_I_CPU1_SB_DQS_DN<5>
J 0
(-5790 4360);
DISPLAY 0.659574 (-5790 4360);
PAINT MONO (-5790 4360);
DISPLAY INVISIBLE (-5790 4360);
FORCEPROP 1 LASTPIN (-5800 4350) BN 5
J 2
(-5788 4358);
DISPLAY 0.489362 (-5788 4358);
PAINT GREEN (-5788 4358);
FORCEPROP 2 LAST CDS_LIB mstr_standard
J 2
(-5850 4350);
DISPLAY 0.723404 (-5850 4350);
PAINT MONO (-5850 4350);
DISPLAY INVISIBLE (-5850 4350);
FORCEPROP 1 LAST BODY_TYPE PLUMBING
J 2
(-5850 4400);
DISPLAY 0.872340 (-5850 4400);
PAINT GREEN (-5850 4400);
DISPLAY INVISIBLE (-5850 4400);
FORCEPROP 1 LAST HDL_TAP TRUE
J 2
(-6175 4225);
DISPLAY 0.872340 (-6175 4225);
DISPLAY INVISIBLE (-6175 4225);
FORCEPROP 1 LAST PATH I278
J 2
(-5848 4350);
DISPLAY 0.872340 (-5848 4350);
PAINT GREEN (-5848 4350);
DISPLAY INVISIBLE (-5848 4350);
FORCEADD TAP..1
R 2
(-5850 4250);
FORCEPROP 3 LASTPIN (-5800 4250) SIG_NAME M_I_CPU1_SB_DQS_DN<6>
J 0
(-5790 4260);
DISPLAY 0.659574 (-5790 4260);
PAINT MONO (-5790 4260);
DISPLAY INVISIBLE (-5790 4260);
FORCEPROP 1 LASTPIN (-5800 4250) BN 6
J 2
(-5788 4258);
DISPLAY 0.489362 (-5788 4258);
PAINT GREEN (-5788 4258);
FORCEPROP 2 LAST CDS_LIB mstr_standard
J 2
(-5850 4250);
DISPLAY 0.723404 (-5850 4250);
PAINT MONO (-5850 4250);
DISPLAY INVISIBLE (-5850 4250);
FORCEPROP 1 LAST BODY_TYPE PLUMBING
J 2
(-5850 4300);
DISPLAY 0.872340 (-5850 4300);
PAINT GREEN (-5850 4300);
DISPLAY INVISIBLE (-5850 4300);
FORCEPROP 1 LAST HDL_TAP TRUE
J 2
(-6175 4125);
DISPLAY 0.872340 (-6175 4125);
DISPLAY INVISIBLE (-6175 4125);
FORCEPROP 1 LAST PATH I279
J 2
(-5848 4250);
DISPLAY 0.872340 (-5848 4250);
PAINT GREEN (-5848 4250);
DISPLAY INVISIBLE (-5848 4250);
FORCEADD TAP..1
R 2
(-5850 4150);
FORCEPROP 3 LASTPIN (-5800 4150) SIG_NAME M_I_CPU1_SB_DQS_DN<7>
J 0
(-5790 4160);
DISPLAY 0.659574 (-5790 4160);
PAINT MONO (-5790 4160);
DISPLAY INVISIBLE (-5790 4160);
FORCEPROP 1 LASTPIN (-5800 4150) BN 7
J 2
(-5788 4158);
DISPLAY 0.489362 (-5788 4158);
PAINT GREEN (-5788 4158);
FORCEPROP 2 LAST CDS_LIB mstr_standard
J 2
(-5850 4150);
DISPLAY 0.723404 (-5850 4150);
PAINT MONO (-5850 4150);
DISPLAY INVISIBLE (-5850 4150);
FORCEPROP 1 LAST BODY_TYPE PLUMBING
J 2
(-5850 4200);
DISPLAY 0.872340 (-5850 4200);
PAINT GREEN (-5850 4200);
DISPLAY INVISIBLE (-5850 4200);
FORCEPROP 1 LAST HDL_TAP TRUE
J 2
(-6175 4025);
DISPLAY 0.872340 (-6175 4025);
DISPLAY INVISIBLE (-6175 4025);
FORCEPROP 1 LAST PATH I280
J 2
(-5848 4150);
DISPLAY 0.872340 (-5848 4150);
PAINT GREEN (-5848 4150);
DISPLAY INVISIBLE (-5848 4150);
FORCEADD OFFPAGE..3
R 2
(-6550 5975);
FORCEPROP 2 LAST $XR0 105 
J 0
(-6830 5975);
DISPLAY 0.638298 (-6830 5975);
PAINT MONO (-6830 5975);
FORCEPROP 2 LAST PATH I281
J 0
(-6825 6025);
DISPLAY 1.021277 (-6825 6025);
DISPLAY INVISIBLE (-6825 6025);
FORCEPROP 1 LAST COMMENT_BODY TRUE
J 2
(-6500 5875);
DISPLAY 0.872340 (-6500 5875);
PAINT GREEN (-6500 5875);
DISPLAY INVISIBLE (-6500 5875);
FORCEPROP 1 LAST OFFPAGE TRUE
J 2
(-6875 5850);
DISPLAY 0.872340 (-6875 5850);
PAINT GREEN (-6875 5850);
DISPLAY INVISIBLE (-6875 5850);
FORCEPROP 2 LAST CDS_LIB standard
J 0
(-6550 5975);
DISPLAY INVISIBLE (-6550 5975);
FORCEADD OFFPAGE..3
R 2
(-6550 5925);
FORCEPROP 2 LAST $XR0 105 
J 0
(-6830 5925);
DISPLAY 0.638298 (-6830 5925);
PAINT MONO (-6830 5925);
FORCEPROP 2 LAST PATH I282
J 0
(-6825 5975);
DISPLAY 1.021277 (-6825 5975);
DISPLAY INVISIBLE (-6825 5975);
FORCEPROP 1 LAST COMMENT_BODY TRUE
J 2
(-6500 5825);
DISPLAY 0.872340 (-6500 5825);
PAINT GREEN (-6500 5825);
DISPLAY INVISIBLE (-6500 5825);
FORCEPROP 1 LAST OFFPAGE TRUE
J 2
(-6875 5800);
DISPLAY 0.872340 (-6875 5800);
PAINT GREEN (-6875 5800);
DISPLAY INVISIBLE (-6875 5800);
FORCEPROP 2 LAST CDS_LIB standard
J 0
(-6550 5925);
DISPLAY INVISIBLE (-6550 5925);
FORCEADD OFFPAGE..3
R 2
(-6550 4925);
FORCEPROP 2 LAST $XR0 105 
J 0
(-6830 4925);
DISPLAY 0.638298 (-6830 4925);
PAINT MONO (-6830 4925);
FORCEPROP 2 LAST PATH I283
J 0
(-6825 4975);
DISPLAY 1.021277 (-6825 4975);
DISPLAY INVISIBLE (-6825 4975);
FORCEPROP 1 LAST COMMENT_BODY TRUE
J 2
(-6500 4825);
DISPLAY 0.872340 (-6500 4825);
PAINT GREEN (-6500 4825);
DISPLAY INVISIBLE (-6500 4825);
FORCEPROP 1 LAST OFFPAGE TRUE
J 2
(-6875 4800);
DISPLAY 0.872340 (-6875 4800);
PAINT GREEN (-6875 4800);
DISPLAY INVISIBLE (-6875 4800);
FORCEPROP 2 LAST CDS_LIB standard
J 0
(-6550 4925);
DISPLAY INVISIBLE (-6550 4925);
FORCEADD OFFPAGE..3
R 2
(-6550 4875);
FORCEPROP 2 LAST $XR0 105 
J 0
(-6830 4875);
DISPLAY 0.638298 (-6830 4875);
PAINT MONO (-6830 4875);
FORCEPROP 2 LAST PATH I284
J 0
(-6825 4925);
DISPLAY 1.021277 (-6825 4925);
DISPLAY INVISIBLE (-6825 4925);
FORCEPROP 1 LAST COMMENT_BODY TRUE
J 2
(-6500 4775);
DISPLAY 0.872340 (-6500 4775);
PAINT GREEN (-6500 4775);
DISPLAY INVISIBLE (-6500 4775);
FORCEPROP 1 LAST OFFPAGE TRUE
J 2
(-6875 4750);
DISPLAY 0.872340 (-6875 4750);
PAINT GREEN (-6875 4750);
DISPLAY INVISIBLE (-6875 4750);
FORCEPROP 2 LAST CDS_LIB standard
J 0
(-6550 4875);
DISPLAY INVISIBLE (-6550 4875);
FORCEADD TAP..1
R 2
(-5650 4000);
FORCEPROP 3 LASTPIN (-5600 4000) SIG_NAME M_I_CPU1_SB_DQS_DP<9>
J 0
(-5590 4010);
DISPLAY 0.659574 (-5590 4010);
PAINT MONO (-5590 4010);
DISPLAY INVISIBLE (-5590 4010);
FORCEPROP 1 LASTPIN (-5600 4000) BN 9
J 2
(-5588 4008);
DISPLAY 0.489362 (-5588 4008);
PAINT GREEN (-5588 4008);
FORCEPROP 2 LAST CDS_LIB mstr_standard
J 2
(-5650 4000);
DISPLAY 0.723404 (-5650 4000);
PAINT MONO (-5650 4000);
DISPLAY INVISIBLE (-5650 4000);
FORCEPROP 1 LAST BODY_TYPE PLUMBING
J 2
(-5650 4050);
DISPLAY 0.872340 (-5650 4050);
PAINT GREEN (-5650 4050);
DISPLAY INVISIBLE (-5650 4050);
FORCEPROP 1 LAST HDL_TAP TRUE
J 2
(-5975 3875);
DISPLAY 0.872340 (-5975 3875);
DISPLAY INVISIBLE (-5975 3875);
FORCEPROP 1 LAST PATH I285
J 2
(-5648 4000);
DISPLAY 0.872340 (-5648 4000);
PAINT GREEN (-5648 4000);
DISPLAY INVISIBLE (-5648 4000);
FORCEADD TAP..1
R 2
(-5850 3950);
FORCEPROP 3 LASTPIN (-5800 3950) SIG_NAME M_I_CPU1_SB_DQS_DN<9>
J 0
(-5790 3960);
DISPLAY 0.659574 (-5790 3960);
PAINT MONO (-5790 3960);
DISPLAY INVISIBLE (-5790 3960);
FORCEPROP 1 LASTPIN (-5800 3950) BN 9
J 2
(-5788 3958);
DISPLAY 0.489362 (-5788 3958);
PAINT GREEN (-5788 3958);
FORCEPROP 2 LAST CDS_LIB mstr_standard
J 2
(-5850 3950);
DISPLAY 0.723404 (-5850 3950);
PAINT MONO (-5850 3950);
DISPLAY INVISIBLE (-5850 3950);
FORCEPROP 1 LAST BODY_TYPE PLUMBING
J 2
(-5850 4000);
DISPLAY 0.872340 (-5850 4000);
PAINT GREEN (-5850 4000);
DISPLAY INVISIBLE (-5850 4000);
FORCEPROP 1 LAST HDL_TAP TRUE
J 2
(-6175 3825);
DISPLAY 0.872340 (-6175 3825);
DISPLAY INVISIBLE (-6175 3825);
FORCEPROP 1 LAST PATH I286
J 2
(-5848 3950);
DISPLAY 0.872340 (-5848 3950);
PAINT GREEN (-5848 3950);
DISPLAY INVISIBLE (-5848 3950);
FORCEADD TAP..1
R 2
(-5850 4050);
FORCEPROP 3 LASTPIN (-5800 4050) SIG_NAME M_I_CPU1_SB_DQS_DN<8>
J 0
(-5790 4060);
DISPLAY 0.659574 (-5790 4060);
PAINT MONO (-5790 4060);
DISPLAY INVISIBLE (-5790 4060);
FORCEPROP 1 LASTPIN (-5800 4050) BN 8
J 2
(-5788 4058);
DISPLAY 0.489362 (-5788 4058);
PAINT GREEN (-5788 4058);
FORCEPROP 2 LAST CDS_LIB mstr_standard
J 2
(-5850 4050);
DISPLAY 0.723404 (-5850 4050);
PAINT MONO (-5850 4050);
DISPLAY INVISIBLE (-5850 4050);
FORCEPROP 1 LAST BODY_TYPE PLUMBING
J 2
(-5850 4100);
DISPLAY 0.872340 (-5850 4100);
PAINT GREEN (-5850 4100);
DISPLAY INVISIBLE (-5850 4100);
FORCEPROP 1 LAST HDL_TAP TRUE
J 2
(-6175 3925);
DISPLAY 0.872340 (-6175 3925);
DISPLAY INVISIBLE (-6175 3925);
FORCEPROP 1 LAST PATH I287
J 2
(-5848 4050);
DISPLAY 0.872340 (-5848 4050);
PAINT GREEN (-5848 4050);
DISPLAY INVISIBLE (-5848 4050);
FORCEADD TAP..1
R 2
(-5850 3750);
FORCEPROP 3 LASTPIN (-5800 3750) SIG_NAME M_I_CPU1_SA_CA<1>
J 0
(-5790 3760);
DISPLAY 0.659574 (-5790 3760);
PAINT MONO (-5790 3760);
DISPLAY INVISIBLE (-5790 3760);
FORCEPROP 1 LASTPIN (-5800 3750) BN 1
J 2
(-5788 3758);
DISPLAY 0.489362 (-5788 3758);
PAINT GREEN (-5788 3758);
FORCEPROP 2 LAST CDS_LIB mstr_standard
J 0
(-5850 3750);
DISPLAY 0.723404 (-5850 3750);
PAINT MONO (-5850 3750);
DISPLAY INVISIBLE (-5850 3750);
FORCEPROP 1 LAST BODY_TYPE PLUMBING
J 2
(-5850 3800);
DISPLAY 0.872340 (-5850 3800);
PAINT GREEN (-5850 3800);
DISPLAY INVISIBLE (-5850 3800);
FORCEPROP 1 LAST HDL_TAP TRUE
J 2
(-6175 3625);
DISPLAY 0.872340 (-6175 3625);
DISPLAY INVISIBLE (-6175 3625);
FORCEPROP 1 LAST PATH I288
J 2
(-5848 3750);
DISPLAY 0.872340 (-5848 3750);
PAINT GREEN (-5848 3750);
DISPLAY INVISIBLE (-5848 3750);
FORCEADD TAP..1
R 2
(-5850 3800);
FORCEPROP 3 LASTPIN (-5800 3800) SIG_NAME M_I_CPU1_SA_CA<0>
J 0
(-5790 3810);
DISPLAY 0.659574 (-5790 3810);
PAINT MONO (-5790 3810);
DISPLAY INVISIBLE (-5790 3810);
FORCEPROP 1 LASTPIN (-5800 3800) BN 0
J 2
(-5788 3808);
DISPLAY 0.489362 (-5788 3808);
PAINT GREEN (-5788 3808);
FORCEPROP 2 LAST CDS_LIB mstr_standard
J 0
(-5850 3800);
DISPLAY 0.723404 (-5850 3800);
PAINT MONO (-5850 3800);
DISPLAY INVISIBLE (-5850 3800);
FORCEPROP 1 LAST BODY_TYPE PLUMBING
J 2
(-5850 3850);
DISPLAY 0.872340 (-5850 3850);
PAINT GREEN (-5850 3850);
DISPLAY INVISIBLE (-5850 3850);
FORCEPROP 1 LAST HDL_TAP TRUE
J 2
(-6175 3675);
DISPLAY 0.872340 (-6175 3675);
DISPLAY INVISIBLE (-6175 3675);
FORCEPROP 1 LAST PATH I289
J 2
(-5848 3800);
DISPLAY 0.872340 (-5848 3800);
PAINT GREEN (-5848 3800);
DISPLAY INVISIBLE (-5848 3800);
FORCEADD TAP..1
R 2
(-5850 3700);
FORCEPROP 3 LASTPIN (-5800 3700) SIG_NAME M_I_CPU1_SA_CA<2>
J 0
(-5790 3710);
DISPLAY 0.659574 (-5790 3710);
PAINT MONO (-5790 3710);
DISPLAY INVISIBLE (-5790 3710);
FORCEPROP 1 LASTPIN (-5800 3700) BN 2
J 2
(-5788 3708);
DISPLAY 0.489362 (-5788 3708);
PAINT GREEN (-5788 3708);
FORCEPROP 2 LAST CDS_LIB mstr_standard
J 0
(-5850 3700);
DISPLAY 0.723404 (-5850 3700);
PAINT MONO (-5850 3700);
DISPLAY INVISIBLE (-5850 3700);
FORCEPROP 1 LAST BODY_TYPE PLUMBING
J 2
(-5850 3750);
DISPLAY 0.872340 (-5850 3750);
PAINT GREEN (-5850 3750);
DISPLAY INVISIBLE (-5850 3750);
FORCEPROP 1 LAST HDL_TAP TRUE
J 2
(-6175 3575);
DISPLAY 0.872340 (-6175 3575);
DISPLAY INVISIBLE (-6175 3575);
FORCEPROP 1 LAST PATH I290
J 2
(-5848 3700);
DISPLAY 0.872340 (-5848 3700);
PAINT GREEN (-5848 3700);
DISPLAY INVISIBLE (-5848 3700);
FORCEADD TAP..1
R 2
(-5850 3650);
FORCEPROP 3 LASTPIN (-5800 3650) SIG_NAME M_I_CPU1_SA_CA<3>
J 0
(-5790 3660);
DISPLAY 0.659574 (-5790 3660);
PAINT MONO (-5790 3660);
DISPLAY INVISIBLE (-5790 3660);
FORCEPROP 1 LASTPIN (-5800 3650) BN 3
J 2
(-5788 3658);
DISPLAY 0.489362 (-5788 3658);
PAINT GREEN (-5788 3658);
FORCEPROP 2 LAST CDS_LIB mstr_standard
J 0
(-5850 3650);
DISPLAY 0.723404 (-5850 3650);
PAINT MONO (-5850 3650);
DISPLAY INVISIBLE (-5850 3650);
FORCEPROP 1 LAST BODY_TYPE PLUMBING
J 2
(-5850 3700);
DISPLAY 0.872340 (-5850 3700);
PAINT GREEN (-5850 3700);
DISPLAY INVISIBLE (-5850 3700);
FORCEPROP 1 LAST HDL_TAP TRUE
J 2
(-6175 3525);
DISPLAY 0.872340 (-6175 3525);
DISPLAY INVISIBLE (-6175 3525);
FORCEPROP 1 LAST PATH I291
J 2
(-5848 3650);
DISPLAY 0.872340 (-5848 3650);
PAINT GREEN (-5848 3650);
DISPLAY INVISIBLE (-5848 3650);
FORCEADD TAP..1
R 2
(-5850 3600);
FORCEPROP 3 LASTPIN (-5800 3600) SIG_NAME M_I_CPU1_SA_CA<4>
J 0
(-5790 3610);
DISPLAY 0.659574 (-5790 3610);
PAINT MONO (-5790 3610);
DISPLAY INVISIBLE (-5790 3610);
FORCEPROP 1 LASTPIN (-5800 3600) BN 4
J 2
(-5788 3608);
DISPLAY 0.489362 (-5788 3608);
PAINT GREEN (-5788 3608);
FORCEPROP 2 LAST CDS_LIB mstr_standard
J 0
(-5850 3600);
DISPLAY 0.723404 (-5850 3600);
PAINT MONO (-5850 3600);
DISPLAY INVISIBLE (-5850 3600);
FORCEPROP 1 LAST BODY_TYPE PLUMBING
J 2
(-5850 3650);
DISPLAY 0.872340 (-5850 3650);
PAINT GREEN (-5850 3650);
DISPLAY INVISIBLE (-5850 3650);
FORCEPROP 1 LAST HDL_TAP TRUE
J 2
(-6175 3475);
DISPLAY 0.872340 (-6175 3475);
DISPLAY INVISIBLE (-6175 3475);
FORCEPROP 1 LAST PATH I292
J 2
(-5848 3600);
DISPLAY 0.872340 (-5848 3600);
PAINT GREEN (-5848 3600);
DISPLAY INVISIBLE (-5848 3600);
FORCEADD TAP..1
R 2
(-5850 3400);
FORCEPROP 3 LASTPIN (-5800 3400) SIG_NAME M_I_CPU1_SB_CA<0>
J 0
(-5790 3410);
DISPLAY 0.659574 (-5790 3410);
PAINT MONO (-5790 3410);
DISPLAY INVISIBLE (-5790 3410);
FORCEPROP 1 LASTPIN (-5800 3400) BN 0
J 2
(-5788 3408);
DISPLAY 0.489362 (-5788 3408);
PAINT GREEN (-5788 3408);
FORCEPROP 2 LAST CDS_LIB mstr_standard
J 0
(-5850 3400);
DISPLAY 0.723404 (-5850 3400);
PAINT MONO (-5850 3400);
DISPLAY INVISIBLE (-5850 3400);
FORCEPROP 1 LAST BODY_TYPE PLUMBING
J 2
(-5850 3450);
DISPLAY 0.872340 (-5850 3450);
PAINT GREEN (-5850 3450);
DISPLAY INVISIBLE (-5850 3450);
FORCEPROP 1 LAST HDL_TAP TRUE
J 2
(-6175 3275);
DISPLAY 0.872340 (-6175 3275);
DISPLAY INVISIBLE (-6175 3275);
FORCEPROP 1 LAST PATH I293
J 2
(-5848 3400);
DISPLAY 0.872340 (-5848 3400);
PAINT GREEN (-5848 3400);
DISPLAY INVISIBLE (-5848 3400);
FORCEADD TAP..1
R 2
(-5850 3350);
FORCEPROP 3 LASTPIN (-5800 3350) SIG_NAME M_I_CPU1_SB_CA<1>
J 0
(-5790 3360);
DISPLAY 0.659574 (-5790 3360);
PAINT MONO (-5790 3360);
DISPLAY INVISIBLE (-5790 3360);
FORCEPROP 1 LASTPIN (-5800 3350) BN 1
J 2
(-5788 3358);
DISPLAY 0.489362 (-5788 3358);
PAINT GREEN (-5788 3358);
FORCEPROP 2 LAST CDS_LIB mstr_standard
J 0
(-5850 3350);
DISPLAY 0.723404 (-5850 3350);
PAINT MONO (-5850 3350);
DISPLAY INVISIBLE (-5850 3350);
FORCEPROP 1 LAST BODY_TYPE PLUMBING
J 2
(-5850 3400);
DISPLAY 0.872340 (-5850 3400);
PAINT GREEN (-5850 3400);
DISPLAY INVISIBLE (-5850 3400);
FORCEPROP 1 LAST HDL_TAP TRUE
J 2
(-6175 3225);
DISPLAY 0.872340 (-6175 3225);
DISPLAY INVISIBLE (-6175 3225);
FORCEPROP 1 LAST PATH I294
J 2
(-5848 3350);
DISPLAY 0.872340 (-5848 3350);
PAINT GREEN (-5848 3350);
DISPLAY INVISIBLE (-5848 3350);
FORCEADD TAP..1
R 2
(-5850 3550);
FORCEPROP 3 LASTPIN (-5800 3550) SIG_NAME M_I_CPU1_SA_CA<5>
J 0
(-5790 3560);
DISPLAY 0.659574 (-5790 3560);
PAINT MONO (-5790 3560);
DISPLAY INVISIBLE (-5790 3560);
FORCEPROP 1 LASTPIN (-5800 3550) BN 5
J 2
(-5788 3558);
DISPLAY 0.489362 (-5788 3558);
PAINT GREEN (-5788 3558);
FORCEPROP 2 LAST CDS_LIB mstr_standard
J 0
(-5850 3550);
DISPLAY 0.723404 (-5850 3550);
PAINT MONO (-5850 3550);
DISPLAY INVISIBLE (-5850 3550);
FORCEPROP 1 LAST BODY_TYPE PLUMBING
J 2
(-5850 3600);
DISPLAY 0.872340 (-5850 3600);
PAINT GREEN (-5850 3600);
DISPLAY INVISIBLE (-5850 3600);
FORCEPROP 1 LAST HDL_TAP TRUE
J 2
(-6175 3425);
DISPLAY 0.872340 (-6175 3425);
DISPLAY INVISIBLE (-6175 3425);
FORCEPROP 1 LAST PATH I295
J 2
(-5848 3550);
DISPLAY 0.872340 (-5848 3550);
PAINT GREEN (-5848 3550);
DISPLAY INVISIBLE (-5848 3550);
FORCEADD TAP..1
R 2
(-5850 3500);
FORCEPROP 3 LASTPIN (-5800 3500) SIG_NAME M_I_CPU1_SA_CA<6>
J 0
(-5790 3510);
DISPLAY 0.659574 (-5790 3510);
PAINT MONO (-5790 3510);
DISPLAY INVISIBLE (-5790 3510);
FORCEPROP 1 LASTPIN (-5800 3500) BN 6
J 2
(-5788 3508);
DISPLAY 0.489362 (-5788 3508);
PAINT GREEN (-5788 3508);
FORCEPROP 2 LAST CDS_LIB mstr_standard
J 0
(-5850 3500);
DISPLAY 0.723404 (-5850 3500);
PAINT MONO (-5850 3500);
DISPLAY INVISIBLE (-5850 3500);
FORCEPROP 1 LAST BODY_TYPE PLUMBING
J 2
(-5850 3550);
DISPLAY 0.872340 (-5850 3550);
PAINT GREEN (-5850 3550);
DISPLAY INVISIBLE (-5850 3550);
FORCEPROP 1 LAST HDL_TAP TRUE
J 2
(-6175 3375);
DISPLAY 0.872340 (-6175 3375);
DISPLAY INVISIBLE (-6175 3375);
FORCEPROP 1 LAST PATH I296
J 2
(-5848 3500);
DISPLAY 0.872340 (-5848 3500);
PAINT GREEN (-5848 3500);
DISPLAY INVISIBLE (-5848 3500);
FORCEADD TAP..1
R 2
(-5850 3300);
FORCEPROP 3 LASTPIN (-5800 3300) SIG_NAME M_I_CPU1_SB_CA<2>
J 0
(-5790 3310);
DISPLAY 0.659574 (-5790 3310);
PAINT MONO (-5790 3310);
DISPLAY INVISIBLE (-5790 3310);
FORCEPROP 1 LASTPIN (-5800 3300) BN 2
J 2
(-5788 3308);
DISPLAY 0.489362 (-5788 3308);
PAINT GREEN (-5788 3308);
FORCEPROP 2 LAST CDS_LIB mstr_standard
J 0
(-5850 3300);
DISPLAY 0.723404 (-5850 3300);
PAINT MONO (-5850 3300);
DISPLAY INVISIBLE (-5850 3300);
FORCEPROP 1 LAST BODY_TYPE PLUMBING
J 2
(-5850 3350);
DISPLAY 0.872340 (-5850 3350);
PAINT GREEN (-5850 3350);
DISPLAY INVISIBLE (-5850 3350);
FORCEPROP 1 LAST HDL_TAP TRUE
J 2
(-6175 3175);
DISPLAY 0.872340 (-6175 3175);
DISPLAY INVISIBLE (-6175 3175);
FORCEPROP 1 LAST PATH I297
J 2
(-5848 3300);
DISPLAY 0.872340 (-5848 3300);
PAINT GREEN (-5848 3300);
DISPLAY INVISIBLE (-5848 3300);
FORCEADD TAP..1
R 2
(-5850 3250);
FORCEPROP 3 LASTPIN (-5800 3250) SIG_NAME M_I_CPU1_SB_CA<3>
J 0
(-5790 3260);
DISPLAY 0.659574 (-5790 3260);
PAINT MONO (-5790 3260);
DISPLAY INVISIBLE (-5790 3260);
FORCEPROP 1 LASTPIN (-5800 3250) BN 3
J 2
(-5788 3258);
DISPLAY 0.489362 (-5788 3258);
PAINT GREEN (-5788 3258);
FORCEPROP 2 LAST CDS_LIB mstr_standard
J 0
(-5850 3250);
DISPLAY 0.723404 (-5850 3250);
PAINT MONO (-5850 3250);
DISPLAY INVISIBLE (-5850 3250);
FORCEPROP 1 LAST BODY_TYPE PLUMBING
J 2
(-5850 3300);
DISPLAY 0.872340 (-5850 3300);
PAINT GREEN (-5850 3300);
DISPLAY INVISIBLE (-5850 3300);
FORCEPROP 1 LAST HDL_TAP TRUE
J 2
(-6175 3125);
DISPLAY 0.872340 (-6175 3125);
DISPLAY INVISIBLE (-6175 3125);
FORCEPROP 1 LAST PATH I298
J 2
(-5848 3250);
DISPLAY 0.872340 (-5848 3250);
PAINT GREEN (-5848 3250);
DISPLAY INVISIBLE (-5848 3250);
FORCEADD TAP..1
R 2
(-5850 3200);
FORCEPROP 3 LASTPIN (-5800 3200) SIG_NAME M_I_CPU1_SB_CA<4>
J 0
(-5790 3210);
DISPLAY 0.659574 (-5790 3210);
PAINT MONO (-5790 3210);
DISPLAY INVISIBLE (-5790 3210);
FORCEPROP 1 LASTPIN (-5800 3200) BN 4
J 2
(-5788 3208);
DISPLAY 0.489362 (-5788 3208);
PAINT GREEN (-5788 3208);
FORCEPROP 2 LAST CDS_LIB mstr_standard
J 0
(-5850 3200);
DISPLAY 0.723404 (-5850 3200);
PAINT MONO (-5850 3200);
DISPLAY INVISIBLE (-5850 3200);
FORCEPROP 1 LAST BODY_TYPE PLUMBING
J 2
(-5850 3250);
DISPLAY 0.872340 (-5850 3250);
PAINT GREEN (-5850 3250);
DISPLAY INVISIBLE (-5850 3250);
FORCEPROP 1 LAST HDL_TAP TRUE
J 2
(-6175 3075);
DISPLAY 0.872340 (-6175 3075);
DISPLAY INVISIBLE (-6175 3075);
FORCEPROP 1 LAST PATH I299
J 2
(-5848 3200);
DISPLAY 0.872340 (-5848 3200);
PAINT GREEN (-5848 3200);
DISPLAY INVISIBLE (-5848 3200);
FORCEADD TAP..1
R 2
(-5850 3150);
FORCEPROP 3 LASTPIN (-5800 3150) SIG_NAME M_I_CPU1_SB_CA<5>
J 0
(-5790 3160);
DISPLAY 0.659574 (-5790 3160);
PAINT MONO (-5790 3160);
DISPLAY INVISIBLE (-5790 3160);
FORCEPROP 1 LASTPIN (-5800 3150) BN 5
J 2
(-5788 3158);
DISPLAY 0.489362 (-5788 3158);
PAINT GREEN (-5788 3158);
FORCEPROP 2 LAST CDS_LIB mstr_standard
J 0
(-5850 3150);
DISPLAY 0.723404 (-5850 3150);
PAINT MONO (-5850 3150);
DISPLAY INVISIBLE (-5850 3150);
FORCEPROP 1 LAST BODY_TYPE PLUMBING
J 2
(-5850 3200);
DISPLAY 0.872340 (-5850 3200);
PAINT GREEN (-5850 3200);
DISPLAY INVISIBLE (-5850 3200);
FORCEPROP 1 LAST HDL_TAP TRUE
J 2
(-6175 3025);
DISPLAY 0.872340 (-6175 3025);
DISPLAY INVISIBLE (-6175 3025);
FORCEPROP 1 LAST PATH I300
J 2
(-5848 3150);
DISPLAY 0.872340 (-5848 3150);
PAINT GREEN (-5848 3150);
DISPLAY INVISIBLE (-5848 3150);
FORCEADD TAP..1
R 2
(-5850 3100);
FORCEPROP 3 LASTPIN (-5800 3100) SIG_NAME M_I_CPU1_SB_CA<6>
J 0
(-5790 3110);
DISPLAY 0.659574 (-5790 3110);
PAINT MONO (-5790 3110);
DISPLAY INVISIBLE (-5790 3110);
FORCEPROP 1 LASTPIN (-5800 3100) BN 6
J 2
(-5788 3108);
DISPLAY 0.489362 (-5788 3108);
PAINT GREEN (-5788 3108);
FORCEPROP 2 LAST CDS_LIB mstr_standard
J 0
(-5850 3100);
DISPLAY 0.723404 (-5850 3100);
PAINT MONO (-5850 3100);
DISPLAY INVISIBLE (-5850 3100);
FORCEPROP 1 LAST BODY_TYPE PLUMBING
J 2
(-5850 3150);
DISPLAY 0.872340 (-5850 3150);
PAINT GREEN (-5850 3150);
DISPLAY INVISIBLE (-5850 3150);
FORCEPROP 1 LAST HDL_TAP TRUE
J 2
(-6175 2975);
DISPLAY 0.872340 (-6175 2975);
DISPLAY INVISIBLE (-6175 2975);
FORCEPROP 1 LAST PATH I301
J 2
(-5848 3100);
DISPLAY 0.872340 (-5848 3100);
PAINT GREEN (-5848 3100);
DISPLAY INVISIBLE (-5848 3100);
FORCEADD OFFPAGE..2
R 2
(-6450 3825);
FORCEPROP 2 LAST $XR0 105 
J 0
(-6705 3825);
DISPLAY 0.638298 (-6705 3825);
PAINT MONO (-6705 3825);
FORCEPROP 2 LAST PATH I302
J 0
(-6700 3875);
DISPLAY 1.021277 (-6700 3875);
DISPLAY INVISIBLE (-6700 3875);
FORCEPROP 1 LAST COMMENT_BODY TRUE
J 2
(-6405 3730);
DISPLAY 0.872340 (-6405 3730);
PAINT GREEN (-6405 3730);
DISPLAY INVISIBLE (-6405 3730);
FORCEPROP 1 LAST OFFPAGE TRUE
J 2
(-6775 3700);
DISPLAY 0.872340 (-6775 3700);
PAINT GREEN (-6775 3700);
DISPLAY INVISIBLE (-6775 3700);
FORCEPROP 2 LAST CDS_LIB standard
J 0
(-6450 3825);
DISPLAY INVISIBLE (-6450 3825);
FORCEADD OFFPAGE..2
R 2
(-6450 3425);
FORCEPROP 2 LAST $XR0 105 
J 0
(-6705 3425);
DISPLAY 0.638298 (-6705 3425);
PAINT MONO (-6705 3425);
FORCEPROP 2 LAST PATH I303
J 0
(-6700 3475);
DISPLAY 1.021277 (-6700 3475);
DISPLAY INVISIBLE (-6700 3475);
FORCEPROP 1 LAST COMMENT_BODY TRUE
J 2
(-6405 3330);
DISPLAY 0.872340 (-6405 3330);
PAINT GREEN (-6405 3330);
DISPLAY INVISIBLE (-6405 3330);
FORCEPROP 1 LAST OFFPAGE TRUE
J 2
(-6775 3300);
DISPLAY 0.872340 (-6775 3300);
PAINT GREEN (-6775 3300);
DISPLAY INVISIBLE (-6775 3300);
FORCEPROP 2 LAST CDS_LIB standard
J 0
(-6450 3425);
DISPLAY INVISIBLE (-6450 3425);
FORCEADD OFFPAGE..2
R 2
(-6450 2950);
FORCEPROP 2 LAST $XR0 105 
J 0
(-6705 2950);
DISPLAY 0.638298 (-6705 2950);
PAINT MONO (-6705 2950);
FORCEPROP 2 LAST PATH I304
J 0
(-6700 3000);
DISPLAY 1.021277 (-6700 3000);
DISPLAY INVISIBLE (-6700 3000);
FORCEPROP 1 LAST COMMENT_BODY TRUE
J 2
(-6405 2855);
DISPLAY 0.872340 (-6405 2855);
PAINT GREEN (-6405 2855);
DISPLAY INVISIBLE (-6405 2855);
FORCEPROP 1 LAST OFFPAGE TRUE
J 2
(-6775 2825);
DISPLAY 0.872340 (-6775 2825);
PAINT GREEN (-6775 2825);
DISPLAY INVISIBLE (-6775 2825);
FORCEPROP 2 LAST CDS_LIB standard
J 0
(-6450 2950);
DISPLAY INVISIBLE (-6450 2950);
FORCEADD OFFPAGE..2
R 2
(-6450 2900);
FORCEPROP 2 LAST $XR0 105 
J 0
(-6705 2900);
DISPLAY 0.638298 (-6705 2900);
PAINT MONO (-6705 2900);
FORCEPROP 2 LAST PATH I305
J 0
(-6700 2950);
DISPLAY 1.021277 (-6700 2950);
DISPLAY INVISIBLE (-6700 2950);
FORCEPROP 1 LAST COMMENT_BODY TRUE
J 2
(-6405 2805);
DISPLAY 0.872340 (-6405 2805);
PAINT GREEN (-6405 2805);
DISPLAY INVISIBLE (-6405 2805);
FORCEPROP 1 LAST OFFPAGE TRUE
J 2
(-6775 2775);
DISPLAY 0.872340 (-6775 2775);
PAINT GREEN (-6775 2775);
DISPLAY INVISIBLE (-6775 2775);
FORCEPROP 2 LAST CDS_LIB standard
J 0
(-6450 2900);
DISPLAY INVISIBLE (-6450 2900);
FORCEADD OFFPAGE..2
R 2
(-6450 2750);
FORCEPROP 2 LAST $XR0 105 
J 0
(-6705 2750);
DISPLAY 0.638298 (-6705 2750);
PAINT MONO (-6705 2750);
FORCEPROP 2 LAST PATH I306
J 0
(-6700 2800);
DISPLAY 1.021277 (-6700 2800);
DISPLAY INVISIBLE (-6700 2800);
FORCEPROP 1 LAST COMMENT_BODY TRUE
J 2
(-6405 2655);
DISPLAY 0.872340 (-6405 2655);
PAINT GREEN (-6405 2655);
DISPLAY INVISIBLE (-6405 2655);
FORCEPROP 1 LAST OFFPAGE TRUE
J 2
(-6775 2625);
DISPLAY 0.872340 (-6775 2625);
PAINT GREEN (-6775 2625);
DISPLAY INVISIBLE (-6775 2625);
FORCEPROP 2 LAST CDS_LIB standard
J 0
(-6450 2750);
DISPLAY INVISIBLE (-6450 2750);
FORCEADD OFFPAGE..1
(-6450 2650);
FORCEPROP 2 LAST $XR0 105 
J 0
(-6732 2650);
DISPLAY 0.638298 (-6732 2650);
PAINT MONO (-6732 2650);
FORCEPROP 2 LAST PATH I307
J 0
(-6725 2700);
DISPLAY 1.021277 (-6725 2700);
DISPLAY INVISIBLE (-6725 2700);
FORCEPROP 1 LAST COMMENT_BODY TRUE
J 0
(-6325 2550);
DISPLAY 0.872340 (-6325 2550);
PAINT GREEN (-6325 2550);
DISPLAY INVISIBLE (-6325 2550);
FORCEPROP 1 LAST OFFPAGE TRUE
J 0
(-6125 2525);
DISPLAY 0.872340 (-6125 2525);
PAINT GREEN (-6125 2525);
DISPLAY INVISIBLE (-6125 2525);
FORCEPROP 2 LAST CDS_LIB standard
J 0
(-6450 2650);
DISPLAY INVISIBLE (-6450 2650);
FORCEADD OFFPAGE..2
R 2
(-6450 2800);
FORCEPROP 2 LAST $XR0 105 
J 0
(-6705 2800);
DISPLAY 0.638298 (-6705 2800);
PAINT MONO (-6705 2800);
FORCEPROP 2 LAST PATH I308
J 0
(-6700 2850);
DISPLAY 1.021277 (-6700 2850);
DISPLAY INVISIBLE (-6700 2850);
FORCEPROP 1 LAST COMMENT_BODY TRUE
J 2
(-6405 2705);
DISPLAY 0.872340 (-6405 2705);
PAINT GREEN (-6405 2705);
DISPLAY INVISIBLE (-6405 2705);
FORCEPROP 1 LAST OFFPAGE TRUE
J 2
(-6775 2675);
DISPLAY 0.872340 (-6775 2675);
PAINT GREEN (-6775 2675);
DISPLAY INVISIBLE (-6775 2675);
FORCEPROP 2 LAST CDS_LIB standard
J 0
(-6450 2800);
DISPLAY INVISIBLE (-6450 2800);
FORCEADD OFFPAGE..5
(-6450 2550);
FORCEPROP 2 LAST $XR0 105 
J 0
(-6705 2550);
DISPLAY 0.638298 (-6705 2550);
PAINT MONO (-6705 2550);
FORCEPROP 2 LAST PATH I309
J 0
(-6700 2600);
DISPLAY 1.021277 (-6700 2600);
DISPLAY INVISIBLE (-6700 2600);
FORCEPROP 1 LAST COMMENT_BODY TRUE
J 0
(-6350 2475);
DISPLAY 0.872340 (-6350 2475);
PAINT GREEN (-6350 2475);
DISPLAY INVISIBLE (-6350 2475);
FORCEPROP 1 LAST OFFPAGE TRUE
J 0
(-6125 2425);
DISPLAY 0.872340 (-6125 2425);
PAINT GREEN (-6125 2425);
DISPLAY INVISIBLE (-6125 2425);
FORCEPROP 2 LAST CDS_LIB mstr_standard
J 0
(-6450 2550);
DISPLAY INVISIBLE (-6450 2550);
FORCEADD OFFPAGE..2
R 2
(-6450 2450);
FORCEPROP 2 LAST $XR0 105 
J 0
(-6705 2450);
DISPLAY 0.638298 (-6705 2450);
PAINT MONO (-6705 2450);
FORCEPROP 2 LAST PATH I310
J 0
(-6700 2500);
DISPLAY 1.021277 (-6700 2500);
DISPLAY INVISIBLE (-6700 2500);
FORCEPROP 1 LAST COMMENT_BODY TRUE
J 2
(-6405 2355);
DISPLAY 0.872340 (-6405 2355);
PAINT GREEN (-6405 2355);
DISPLAY INVISIBLE (-6405 2355);
FORCEPROP 1 LAST OFFPAGE TRUE
J 2
(-6775 2325);
DISPLAY 0.872340 (-6775 2325);
PAINT GREEN (-6775 2325);
DISPLAY INVISIBLE (-6775 2325);
FORCEPROP 2 LAST CDS_LIB standard
J 0
(-6450 2450);
DISPLAY INVISIBLE (-6450 2450);
FORCEADD OFFPAGE..2
R 2
(-6450 2400);
FORCEPROP 2 LAST $XR0 105 
J 0
(-6705 2400);
DISPLAY 0.638298 (-6705 2400);
PAINT MONO (-6705 2400);
FORCEPROP 2 LAST PATH I311
J 0
(-6700 2450);
DISPLAY 1.021277 (-6700 2450);
DISPLAY INVISIBLE (-6700 2450);
FORCEPROP 1 LAST COMMENT_BODY TRUE
J 2
(-6405 2305);
DISPLAY 0.872340 (-6405 2305);
PAINT GREEN (-6405 2305);
DISPLAY INVISIBLE (-6405 2305);
FORCEPROP 1 LAST OFFPAGE TRUE
J 2
(-6775 2275);
DISPLAY 0.872340 (-6775 2275);
PAINT GREEN (-6775 2275);
DISPLAY INVISIBLE (-6775 2275);
FORCEPROP 2 LAST CDS_LIB standard
J 0
(-6450 2400);
DISPLAY INVISIBLE (-6450 2400);
FORCEADD OFFPAGE..1
(-6450 2300);
FORCEPROP 2 LAST $XR0 105 
J 0
(-6732 2300);
DISPLAY 0.638298 (-6732 2300);
PAINT MONO (-6732 2300);
FORCEPROP 2 LAST PATH I312
J 0
(-6725 2350);
DISPLAY 1.021277 (-6725 2350);
DISPLAY INVISIBLE (-6725 2350);
FORCEPROP 1 LAST COMMENT_BODY TRUE
J 0
(-6325 2200);
DISPLAY 0.872340 (-6325 2200);
PAINT GREEN (-6325 2200);
DISPLAY INVISIBLE (-6325 2200);
FORCEPROP 1 LAST OFFPAGE TRUE
J 0
(-6125 2175);
DISPLAY 0.872340 (-6125 2175);
PAINT GREEN (-6125 2175);
DISPLAY INVISIBLE (-6125 2175);
FORCEPROP 2 LAST CDS_LIB standard
J 0
(-6450 2300);
DISPLAY INVISIBLE (-6450 2300);
FORCEADD OFFPAGE..5
(-6450 2200);
FORCEPROP 2 LAST $XR0 105 
J 0
(-6705 2200);
DISPLAY 0.638298 (-6705 2200);
PAINT MONO (-6705 2200);
FORCEPROP 2 LAST PATH I313
J 0
(-6700 2250);
DISPLAY 1.021277 (-6700 2250);
DISPLAY INVISIBLE (-6700 2250);
FORCEPROP 1 LAST COMMENT_BODY TRUE
J 0
(-6350 2125);
DISPLAY 0.872340 (-6350 2125);
PAINT GREEN (-6350 2125);
DISPLAY INVISIBLE (-6350 2125);
FORCEPROP 1 LAST OFFPAGE TRUE
J 0
(-6125 2075);
DISPLAY 0.872340 (-6125 2075);
PAINT GREEN (-6125 2075);
DISPLAY INVISIBLE (-6125 2075);
FORCEPROP 2 LAST CDS_LIB standard
J 0
(-6450 2200);
DISPLAY INVISIBLE (-6450 2200);
FORCEADD Q_RES..1
(-6525 2100);
FORCEPROP 1 LAST LOCATION R508
J 0
(-6850 2100);
DISPLAY 0.489362 (-6850 2100);
PAINT SKYBLUE (-6850 2100);
FORCEPROP 0 LAST $SEC 1
J 0
(-6700 2150);
DISPLAY 0.680851 (-6700 2150);
PAINT MONO (-6700 2150);
DISPLAY INVISIBLE (-6700 2150);
FORCEPROP 0 LAST CDS_SEC 1
J 0
(-6700 2150);
DISPLAY 1.021277 (-6700 2150);
DISPLAY INVISIBLE (-6700 2150);
FORCEPROP 1 LASTPIN (-6625 2100) $PN 1
J 0
(-6613 2112);
DISPLAY 0.489362 (-6613 2112);
PAINT MONO (-6613 2112);
FORCEPROP 1 LASTPIN (-6425 2100) $PN 2
J 0
(-6463 2112);
DISPLAY 0.489362 (-6463 2112);
PAINT MONO (-6463 2112);
FORCEPROP 1 LAST TOLERANCE 1%
J 0
(-6250 2100);
DISPLAY 0.489362 (-6250 2100);
PAINT SKYBLUE (-6250 2100);
FORCEPROP 1 LAST VALUE 15   
J 2
(-6200 2100);
DISPLAY 0.489362 (-6200 2100);
PAINT SKYBLUE (-6200 2100);
FORCEPROP 1 LAST PART_NUMBER CS01502FB11
J 0
(-6425 2075);
DISPLAY 0.489362 (-6425 2075);
PAINT SKYBLUE (-6425 2075);
FORCEPROP 1 LAST PACK_TYPE 0402LF
J 0
(-6850 2075);
DISPLAY 0.489362 (-6850 2075);
PAINT SKYBLUE (-6850 2075);
FORCEPROP 2 LAST CDS_LIB pure_quanta
J 0
(-6525 2100);
DISPLAY INVISIBLE (-6525 2100);
FORCEPROP 1 LAST PATH I314
J 0
(-6575 2250);
DISPLAY 0.978723 (-6575 2250);
PAINT WHITE (-6575 2250);
DISPLAY INVISIBLE (-6575 2250);
FORCEPROP 1 LAST WATTAGE 1/16W
J 2
(-6300 2225);
DISPLAY 0.638298 (-6300 2225);
PAINT SKYBLUE (-6300 2225);
DISPLAY INVISIBLE (-6300 2225);
FORCEPROP 1 LAST MATERIAL CHIP
J 0
(-6650 2225);
DISPLAY 0.638298 (-6650 2225);
PAINT SKYBLUE (-6650 2225);
DISPLAY INVISIBLE (-6650 2225);
FORCEADD OFFPAGE..1
(-7400 2100);
FORCEPROP 2 LAST $XR0 105 
J 0
(-7652 2100);
DISPLAY 0.638298 (-7652 2100);
PAINT MONO (-7652 2100);
FORCEPROP 2 LAST PATH I315
J 0
(-7650 2150);
DISPLAY 1.021277 (-7650 2150);
DISPLAY INVISIBLE (-7650 2150);
FORCEPROP 1 LAST COMMENT_BODY TRUE
J 0
(-7275 2000);
DISPLAY 0.872340 (-7275 2000);
PAINT GREEN (-7275 2000);
DISPLAY INVISIBLE (-7275 2000);
FORCEPROP 1 LAST OFFPAGE TRUE
J 0
(-7075 1975);
DISPLAY 0.872340 (-7075 1975);
PAINT GREEN (-7075 1975);
DISPLAY INVISIBLE (-7075 1975);
FORCEPROP 2 LAST CDS_LIB mstr_standard
J 0
(-7400 2100);
DISPLAY INVISIBLE (-7400 2100);
FORCEADD OFFPAGE..5
(-6450 2000);
FORCEPROP 2 LAST $XR0 105 
J 0
(-6705 2000);
DISPLAY 0.638298 (-6705 2000);
PAINT MONO (-6705 2000);
FORCEPROP 2 LAST PATH I316
J 0
(-6700 2050);
DISPLAY 1.021277 (-6700 2050);
DISPLAY INVISIBLE (-6700 2050);
FORCEPROP 1 LAST COMMENT_BODY TRUE
J 0
(-6350 1925);
DISPLAY 0.872340 (-6350 1925);
PAINT GREEN (-6350 1925);
DISPLAY INVISIBLE (-6350 1925);
FORCEPROP 1 LAST OFFPAGE TRUE
J 0
(-6125 1875);
DISPLAY 0.872340 (-6125 1875);
PAINT GREEN (-6125 1875);
DISPLAY INVISIBLE (-6125 1875);
FORCEPROP 2 LAST CDS_LIB standard
J 0
(-6450 2000);
DISPLAY INVISIBLE (-6450 2000);
FORCEADD CAD_NOTE..1
(-7550 2375);
FORCEPROP 0 LAST L1 R1984 PLACE CLOSE TO CPU < 25MM
J 0
(-7700 2250);
DISPLAY 0.617021 (-7700 2250);
PAINT WHITE (-7700 2250);
FORCEPROP 2 LAST CDS_LIB pure_quanta_power
J 0
(-7550 2375);
DISPLAY INVISIBLE (-7550 2375);
FORCEPROP 1 LAST COMMENT_BODY TRUE
J 0
(-7525 2475);
DISPLAY 0.574468 (-7525 2475);
PAINT WHITE (-7525 2475);
DISPLAY INVISIBLE (-7525 2475);
FORCEADD QUANTA_TITLE_BLOCK_C..1
(0 0);
FORCEPROP 0 LAST CDS_CON_LAST_MODIFIED Fri Mar 11 14:52:33 2022
J 0
(-1885 15);
DISPLAY INVISIBLE (-1885 15);
FORCEPROP 1 LAST CUSTOM_TXT_CDS <CON_LAST_MODIFIED>
J 0
(-1885 15);
DISPLAY 0.978723 (-1885 15);
FORCEPROP 2 LAST CUSTOM_TXT_CDS <XR_PAGE_TITLE>
J 0
(-7890 5250);
DISPLAY 0.638298 (-7890 5250);
PAINT PINK (-7890 5250);
DISPLAY INVISIBLE (-7890 5250);
FORCEPROP 1 LAST CUSTOM_TXT_CDS <NAME_2>
J 0
(-3175 50);
FORCEPROP 1 LAST CUSTOM_TXT_CDS <NAME_1>
J 0
(-3175 175);
FORCEPROP 1 LAST CUSTOM_TXT_CDS <Q_NUMBER>
J 0
(-1403 103);
DISPLAY 1.212766 (-1403 103);
FORCEPROP 1 LAST CUSTOM_TXT_CDS <Q_PROJ>
J 0
(-2382 102);
DISPLAY 1.212766 (-2382 102);
FORCEPROP 1 LAST CUSTOM_TXT_CDS <Q_REV>
J 0
(-184 103);
DISPLAY 1.212766 (-184 103);
FORCEPROP 1 LAST CUSTOM_TXT_CDS <CON_PAGE_NUM> OF <CON_TOTAL_PAGES>
J 0
(-446 18);
DISPLAY 0.978723 (-446 18);
FORCEPROP 1 LAST Q_TITLE CPU1 DDR CHI
J 0
(-9366 26);
DISPLAY 2.446809 (-9366 26);
PAINT GREEN (-9366 26);
FORCEPROP 1 LAST Q_DEPT BU9
J 1
(-3763 49);
DISPLAY 1.957447 (-3763 49);
PAINT GREEN (-3763 49);
FORCEPROP 2 LAST PAGE_BORDER TRUE
J 0
(-7890 5250);
DISPLAY 0.638298 (-7890 5250);
PAINT PINK (-7890 5250);
DISPLAY INVISIBLE (-7890 5250);
FORCEPROP 1 LAST CDS_LMAN_SYM_OUTLINE -9475,6775,100,-125
J 0
(0 0);
DISPLAY 0.468085 (0 0);
PAINT GREEN (0 0);
DISPLAY INVISIBLE (0 0);
FORCEPROP 2 LAST CDS_LIB pure_quanta
J 0
(0 0);
DISPLAY INVISIBLE (0 0);
FORCEPROP 1 LAST COMMENT_BODY TRUE
J 0
(12 -13);
DISPLAY 0.978723 (12 -13);
PAINT GREEN (12 -13);
DISPLAY INVISIBLE (12 -13);
FORCEPROP 2 LAST CDS_XR_PAGE_TITLE CR-45 : @T6G_MB_LIB.T6G(SCH_1):PAGE45
J 0
(-7890 5250);
DISPLAY 0.638298 (-7890 5250);
PAINT PINK (-7890 5250);
DISPLAY INVISIBLE (-7890 5250);
WIRE 17 -1 (-3175 5675)(-3175 5625);
WIRE 17 -1 (-3175 5725)(-3175 5675);
WIRE 17 -1 (-3175 5625)(-3175 5525);
WIRE 17 -1 (-3175 5525)(-3175 5475);
WIRE 17 -1 (-3175 5775)(-3175 5725);
WIRE 17 -1 (-3175 5825)(-3175 5775);
WIRE 17 -1 (-3175 5475)(-3175 5425);
WIRE 17 -1 (-3175 5425)(-3175 5375);
WIRE 17 -1 (-3175 5875)(-3175 5825);
WIRE 17 -1 (-3175 5925)(-3175 5875);
WIRE 17 -1 (-3175 5375)(-3175 5325);
WIRE 17 -1 (-3175 5325)(-3175 5275);
WIRE 17 -1 (-3175 5975)(-3175 5925);
WIRE 17 -1 (-3175 5975)(-2550 5975);
FORCEPROP 2 LAST SIG_NAME M_I_CPU1_SA_DQ<31:0>
J 2
(-2610 5985);
DISPLAY 0.489362 (-2610 5985);
WIRE 17 -1 (-3175 5275)(-3175 5225);
WIRE 17 -1 (-3175 5225)(-3175 5175);
WIRE 17 -1 (-3175 5075)(-3175 5175);
WIRE 17 -1 (-3175 5025)(-3175 5075);
WIRE 17 -1 (-3175 4975)(-3175 5025);
WIRE 17 -1 (-3175 4925)(-3175 4975);
WIRE 17 -1 (-3175 4925)(-3175 4875);
WIRE 17 -1 (-3175 4875)(-3175 4825);
WIRE 17 -1 (-3175 4825)(-3175 4775);
WIRE 17 -1 (-3175 4775)(-3175 4725);
WIRE 17 -1 (-3175 4725)(-3175 4625);
WIRE 17 -1 (-3175 4625)(-3175 4575);
WIRE 17 -1 (-3175 4575)(-3175 4525);
WIRE 17 -1 (-3175 4525)(-3175 4475);
WIRE 17 -1 (-3175 4425)(-3175 4475);
WIRE 17 -1 (-3175 4375)(-3175 4425);
WIRE 17 -1 (-3175 4325)(-3175 4375);
WIRE 17 -1 (-3175 4275)(-3175 4325);
WIRE 17 -1 (-3175 4175)(-3175 4125);
WIRE 17 -1 (-3175 4175)(-2550 4175);
FORCEPROP 2 LAST SIG_NAME M_I_CPU1_SB_DQ<31:0>
J 2
(-2610 4185);
DISPLAY 0.489362 (-2610 4185);
WIRE 17 -1 (-3175 3525)(-3175 3475);
WIRE 17 -1 (-3175 3575)(-3175 3525);
WIRE 17 -1 (-3175 3475)(-3175 3425);
WIRE 17 -1 (-3175 3425)(-3175 3375);
WIRE 17 -1 (-3175 3625)(-3175 3575);
WIRE 17 -1 (-3175 3675)(-3175 3625);
WIRE 17 -1 (-3175 3275)(-3175 3375);
WIRE 17 -1 (-3175 3225)(-3175 3275);
WIRE 17 -1 (-3175 3725)(-3175 3675);
WIRE 17 -1 (-3175 3825)(-3175 3725);
WIRE 17 -1 (-3175 3175)(-3175 3225);
WIRE 17 -1 (-3175 3125)(-3175 3175);
WIRE 17 -1 (-3175 3875)(-3175 3825);
WIRE 17 -1 (-3175 3925)(-3175 3875);
WIRE 17 -1 (-3175 3125)(-3175 3075);
WIRE 17 -1 (-3175 3075)(-3175 3025);
WIRE 17 -1 (-3175 3975)(-3175 3925);
WIRE 17 -1 (-3175 4025)(-3175 3975);
WIRE 17 -1 (-3175 3025)(-3175 2975);
WIRE 17 -1 (-3175 2975)(-3175 2925);
WIRE 17 -1 (-3175 4075)(-3175 4025);
WIRE 17 -1 (-3175 4125)(-3175 4075);
WIRE 17 -1 (-3175 2925)(-3175 2825);
WIRE 17 -1 (-3175 2825)(-3175 2775);
WIRE 17 -1 (-3175 2775)(-3175 2725);
WIRE 17 -1 (-3175 2725)(-3175 2675);
WIRE 17 -1 (-3175 2625)(-3175 2675);
WIRE 17 -1 (-3175 2575)(-3175 2625);
WIRE 17 -1 (-3175 2525)(-3175 2575);
WIRE 17 -1 (-3175 2475)(-3175 2525);
WIRE 17 -1 (-3175 2375)(-3175 2400);
WIRE 17 -1 (-3175 2375)(-3175 2325);
WIRE 17 -1 (-3175 2400)(-2675 2400);
FORCEPROP 2 LAST SIG_NAME M_I_CPU1_SA_CB<7:0>
J 2
(-2675 2410);
DISPLAY 0.489362 (-2675 2410);
WIRE 17 -1 (-3175 2275)(-3175 2325);
WIRE 17 -1 (-3175 2275)(-3175 2225);
WIRE 17 -1 (-3175 2175)(-3175 2225);
WIRE 17 -1 (-3175 2125)(-3175 2175);
WIRE 17 -1 (-3175 2075)(-3175 2125);
WIRE 17 -1 (-3175 2025)(-3175 2075);
WIRE 17 -1 (-3175 1825)(-3175 1775);
WIRE 17 -1 (-3175 1825)(-3175 1875);
WIRE 17 -1 (-3175 1725)(-3175 1775);
WIRE 17 -1 (-3175 1675)(-3175 1725);
WIRE 17 -1 (-3175 1925)(-3175 1875);
WIRE 17 -1 (-3175 1925)(-3175 1950);
WIRE 17 -1 (-3175 1625)(-3175 1675);
WIRE 17 -1 (-3175 1575)(-3175 1625);
WIRE 17 -1 (-3175 1950)(-2675 1950);
FORCEPROP 2 LAST SIG_NAME M_I_CPU1_SB_CB<7:0>
J 2
(-2675 1960);
DISPLAY 0.489362 (-2675 1960);
WIRE 17 -1 (-5700 5875)(-5700 5775);
WIRE 17 -1 (-5700 5975)(-5700 5875);
WIRE 17 -1 (-5700 5775)(-5700 5675);
WIRE 17 -1 (-5700 5675)(-5700 5575);
WIRE 17 -1 (-5700 5975)(-6500 5975);
FORCEPROP 2 LAST SIG_NAME M_I_CPU1_SA_DQS_DP<9:0>
J 2
(-5935 5985);
DISPLAY 0.489362 (-5935 5985);
WIRE 17 -1 (-5700 5475)(-5700 5575);
WIRE 17 -1 (-5700 5375)(-5700 5475);
WIRE 17 -1 (-5700 5275)(-5700 5375);
WIRE 17 -1 (-5700 5275)(-5700 5175);
WIRE 17 -1 (-5700 5175)(-5700 5075);
WIRE 17 -1 (-5900 5425)(-5900 5525);
WIRE 17 -1 (-5900 5325)(-5900 5425);
WIRE 17 -1 (-5900 5625)(-5900 5525);
WIRE 17 -1 (-5900 5725)(-5900 5625);
WIRE 17 -1 (-5900 5225)(-5900 5325);
WIRE 17 -1 (-5900 5225)(-5900 5125);
WIRE 17 -1 (-5900 5825)(-5900 5725);
WIRE 17 -1 (-5900 5925)(-5900 5825);
FORCEPROP 2 LAST SIG_NAME M_I_CPU1_SA_DQS_DN<9:0>
J 2
(-5935 5935);
DISPLAY 0.489362 (-5935 5935);
WIRE 17 -1 (-5900 5125)(-5900 5025);
WIRE 17 -1 (-5700 4925)(-5700 4825);
WIRE 17 -1 (-5700 4925)(-6500 4925);
FORCEPROP 2 LAST SIG_NAME M_I_CPU1_SB_DQS_DP<9:0>
J 2
(-5935 4935);
DISPLAY 0.489362 (-5935 4935);
WIRE 17 -1 (-5700 4825)(-5700 4725);
WIRE 17 -1 (-5700 4725)(-5700 4625);
WIRE 17 -1 (-5700 4625)(-5700 4525);
WIRE 17 -1 (-5700 4425)(-5700 4525);
WIRE 17 -1 (-5700 4325)(-5700 4425);
WIRE 17 -1 (-5700 4225)(-5700 4325);
WIRE 17 -1 (-5700 4225)(-5700 4125);
WIRE 17 -1 (-5700 4125)(-5700 4025);
WIRE 17 -1 (-5900 4875)(-5900 4775);
FORCEPROP 2 LAST SIG_NAME M_I_CPU1_SB_DQS_DN<9:0>
J 2
(-5935 4885);
DISPLAY 0.489362 (-5935 4885);
WIRE 17 -1 (-5900 4675)(-5900 4575);
WIRE 17 -1 (-5900 4775)(-5900 4675);
WIRE 17 -1 (-5900 4575)(-5900 4475);
WIRE 17 -1 (-5900 4375)(-5900 4475);
WIRE 17 -1 (-5900 4275)(-5900 4375);
WIRE 17 -1 (-5900 4175)(-5900 4275);
WIRE 17 -1 (-5900 4175)(-5900 4075);
WIRE 17 -1 (-5900 4075)(-5900 3975);
WIRE 17 -1 (-5900 3775)(-5900 3825);
WIRE 17 -1 (-5900 3725)(-5900 3775);
WIRE 17 -1 (-5900 3825)(-6400 3825);
FORCEPROP 2 LAST SIG_NAME M_I_CPU1_SA_CA<6:0>
J 0
(-6400 3835);
DISPLAY 0.489362 (-6400 3835);
WIRE 17 -1 (-5900 3375)(-5900 3425);
WIRE 17 -1 (-5900 3325)(-5900 3375);
WIRE 17 -1 (-5900 3425)(-6400 3425);
FORCEPROP 2 LAST SIG_NAME M_I_CPU1_SB_CA<6:0>
J 0
(-6400 3435);
DISPLAY 0.489362 (-6400 3435);
WIRE 17 -1 (-5900 3675)(-5900 3725);
WIRE 17 -1 (-5900 3275)(-5900 3325);
WIRE 17 -1 (-5900 3625)(-5900 3675);
WIRE 17 -1 (-5900 3575)(-5900 3625);
WIRE 17 -1 (-5900 3525)(-5900 3575);
WIRE 17 -1 (-5900 3225)(-5900 3275);
WIRE 17 -1 (-5900 3175)(-5900 3225);
WIRE 17 -1 (-5900 3125)(-5900 3175);
WIRE 17 -1 (-5900 5925)(-6500 5925);
WIRE 17 -1 (-5900 4875)(-6500 4875);
WIRE 16 -1 (-7350 2100)(-6625 2100);
FORCEPROP 2 LAST SIG_NAME M_I_CPU1_ALERT_N
J 0
(-7310 2110);
DISPLAY 0.489362 (-7310 2110);
WIRE 16 -1 (-6400 1150)(-5300 1150);
FORCEPROP 2 LAST SIG_NAME TP_M_I_CPU1_SA_TEST39I
J 0
(-6385 1160);
DISPLAY 0.489362 (-6385 1160);
FORCEPROP 2 LASTPROP $XRERR UNIQUE?
J 0
(-6640 1150);
DISPLAY 0.638298 (-6640 1150);
PAINT MONO (-6640 1150);
DISPLAY INVISIBLE (-6640 1150);
WIRE 16 -1 (-6425 2100)(-5300 2100);
FORCEPROP 2 LAST SIG_NAME M_I_CPU1_ALERT_R_N
J 0
(-6135 2110);
DISPLAY 0.489362 (-6135 2110);
FORCEPROP 2 LASTPROP $XRERR UNIQUE?
J 0
(-6375 2110);
DISPLAY 0.638298 (-6375 2110);
PAINT MONO (-6375 2110);
DISPLAY INVISIBLE (-6375 2110);
WIRE 16 -1 (-6400 2950)(-5300 2950);
FORCEPROP 2 LAST SIG_NAME M_I_CPU1_CLK_DP<0>
J 0
(-6400 2960);
DISPLAY 0.489362 (-6400 2960);
WIRE 16 -1 (-6400 2900)(-5300 2900);
FORCEPROP 2 LAST SIG_NAME M_I_CPU1_CLK_DN<0>
J 0
(-6400 2910);
DISPLAY 0.489362 (-6400 2910);
WIRE 16 -1 (-6400 2750)(-5300 2750);
FORCEPROP 2 LAST SIG_NAME M_I_CPU1_SA_CS_N<1>
J 0
(-6400 2760);
DISPLAY 0.489362 (-6400 2760);
WIRE 16 -1 (-6400 2650)(-5300 2650);
FORCEPROP 2 LAST SIG_NAME M_I_CPU1_SA_RSP<0>
J 0
(-6400 2660);
DISPLAY 0.489362 (-6400 2660);
WIRE 16 -1 (-6400 2800)(-5300 2800);
FORCEPROP 2 LAST SIG_NAME M_I_CPU1_SA_CS_N<0>
J 0
(-6400 2810);
DISPLAY 0.489362 (-6400 2810);
WIRE 16 -1 (-6400 2550)(-5300 2550);
FORCEPROP 2 LAST SIG_NAME M_I_CPU1_SA_PAR
J 0
(-6400 2560);
DISPLAY 0.489362 (-6400 2560);
WIRE 16 -1 (-6400 2450)(-5300 2450);
FORCEPROP 2 LAST SIG_NAME M_I_CPU1_SB_CS_N<0>
J 0
(-6400 2460);
DISPLAY 0.489362 (-6400 2460);
WIRE 16 -1 (-6400 2400)(-5300 2400);
FORCEPROP 2 LAST SIG_NAME M_I_CPU1_SB_CS_N<1>
J 0
(-6400 2410);
DISPLAY 0.489362 (-6400 2410);
WIRE 16 -1 (-6400 2300)(-5300 2300);
FORCEPROP 2 LAST SIG_NAME M_I_CPU1_SB_RSP<0>
J 0
(-6400 2310);
DISPLAY 0.489362 (-6400 2310);
WIRE 16 -1 (-6400 2200)(-5300 2200);
FORCEPROP 2 LAST SIG_NAME M_I_CPU1_SB_PAR
J 0
(-6400 2210);
DISPLAY 0.489362 (-6400 2210);
WIRE 16 -1 (-6400 2000)(-5300 2000);
FORCEPROP 2 LAST SIG_NAME M_I_CPU1_RESET_N
J 0
(-6400 2010);
DISPLAY 0.489362 (-6400 2010);
WIRE 16 -1 (-5800 3950)(-5300 3950);
WIRE 16 -1 (-5800 4050)(-5300 4050);
WIRE 16 -1 (-5800 3100)(-5300 3100);
WIRE 16 -1 (-5800 3500)(-5300 3500);
WIRE 16 -1 (-5800 3150)(-5300 3150);
WIRE 16 -1 (-5800 3550)(-5300 3550);
WIRE 16 -1 (-5800 3200)(-5300 3200);
WIRE 16 -1 (-5800 3600)(-5300 3600);
WIRE 16 -1 (-5800 3250)(-5300 3250);
WIRE 16 -1 (-5800 3650)(-5300 3650);
WIRE 16 -1 (-5800 3300)(-5300 3300);
WIRE 16 -1 (-5800 3700)(-5300 3700);
WIRE 16 -1 (-5800 3350)(-5300 3350);
WIRE 16 -1 (-5800 3750)(-5300 3750);
WIRE 16 -1 (-5800 3400)(-5300 3400);
WIRE 16 -1 (-5800 3800)(-5300 3800);
WIRE 16 -1 (-5600 4000)(-5300 4000);
WIRE 16 -1 (-5800 4150)(-5300 4150);
WIRE 16 -1 (-5800 4250)(-5300 4250);
WIRE 16 -1 (-5800 4350)(-5300 4350);
WIRE 16 -1 (-5800 4450)(-5300 4450);
WIRE 16 -1 (-5800 5000)(-5300 5000);
WIRE 16 -1 (-5800 4550)(-5300 4550);
WIRE 16 -1 (-5800 5100)(-5300 5100);
WIRE 16 -1 (-5800 4650)(-5300 4650);
WIRE 16 -1 (-5800 4750)(-5300 4750);
WIRE 16 -1 (-5800 4850)(-5300 4850);
WIRE 16 -1 (-5600 4100)(-5300 4100);
WIRE 16 -1 (-5600 4200)(-5300 4200);
WIRE 16 -1 (-5600 4300)(-5300 4300);
WIRE 16 -1 (-5600 4400)(-5300 4400);
WIRE 16 -1 (-5600 4500)(-5300 4500);
WIRE 16 -1 (-5600 4600)(-5300 4600);
WIRE 16 -1 (-5600 5050)(-5300 5050);
WIRE 16 -1 (-5600 4700)(-5300 4700);
WIRE 16 -1 (-5600 4800)(-5300 4800);
WIRE 16 -1 (-5600 4900)(-5300 4900);
WIRE 16 -1 (-5800 5500)(-5300 5500);
WIRE 16 -1 (-5800 5600)(-5300 5600);
WIRE 16 -1 (-5800 5700)(-5300 5700);
WIRE 16 -1 (-5800 5800)(-5300 5800);
WIRE 16 -1 (-5800 5900)(-5300 5900);
WIRE 16 -1 (-5800 5200)(-5300 5200);
WIRE 16 -1 (-5800 5300)(-5300 5300);
WIRE 16 -1 (-5800 5400)(-5300 5400);
WIRE 16 -1 (-5600 5150)(-5300 5150);
WIRE 16 -1 (-5600 5250)(-5300 5250);
WIRE 16 -1 (-5600 5350)(-5300 5350);
WIRE 16 -1 (-5600 5450)(-5300 5450);
WIRE 16 -1 (-5600 5550)(-5300 5550);
WIRE 16 -1 (-5600 5950)(-5300 5950);
WIRE 16 -1 (-5600 5650)(-5300 5650);
WIRE 16 -1 (-5600 5750)(-5300 5750);
WIRE 16 -1 (-5600 5850)(-5300 5850);
WIRE 16 -1 (-3700 1800)(-3275 1800);
WIRE 16 -1 (-3700 2000)(-3275 2000);
WIRE 16 -1 (-3700 1850)(-3275 1850);
WIRE 16 -1 (-3700 1900)(-3275 1900);
WIRE 16 -1 (-3700 1550)(-3275 1550);
WIRE 16 -1 (-3700 1600)(-3275 1600);
WIRE 16 -1 (-3700 1650)(-3275 1650);
WIRE 16 -1 (-3700 1700)(-3275 1700);
WIRE 16 -1 (-3700 1750)(-3275 1750);
WIRE 16 -1 (-3700 2950)(-3275 2950);
WIRE 16 -1 (-3700 3000)(-3275 3000);
WIRE 16 -1 (-3700 2050)(-3275 2050);
WIRE 16 -1 (-3700 3050)(-3275 3050);
WIRE 16 -1 (-3700 2450)(-3275 2450);
WIRE 16 -1 (-3700 2100)(-3275 2100);
WIRE 16 -1 (-3700 2500)(-3275 2500);
WIRE 16 -1 (-3700 2150)(-3275 2150);
WIRE 16 -1 (-3700 2200)(-3275 2200);
WIRE 16 -1 (-3700 2250)(-3275 2250);
WIRE 16 -1 (-3700 2300)(-3275 2300);
WIRE 16 -1 (-3700 2350)(-3275 2350);
WIRE 16 -1 (-3700 2550)(-3275 2550);
WIRE 16 -1 (-3700 2600)(-3275 2600);
WIRE 16 -1 (-3700 2650)(-3275 2650);
WIRE 16 -1 (-3700 2700)(-3275 2700);
WIRE 16 -1 (-3700 2750)(-3275 2750);
WIRE 16 -1 (-3700 2800)(-3275 2800);
WIRE 16 -1 (-3700 2900)(-3275 2900);
WIRE 16 -1 (-3700 3900)(-3275 3900);
WIRE 16 -1 (-3700 3550)(-3275 3550);
WIRE 16 -1 (-3700 3950)(-3275 3950);
WIRE 16 -1 (-3700 3600)(-3275 3600);
WIRE 16 -1 (-3700 4000)(-3275 4000);
WIRE 16 -1 (-3700 4050)(-3275 4050);
WIRE 16 -1 (-3700 3100)(-3275 3100);
WIRE 16 -1 (-3700 3150)(-3275 3150);
WIRE 16 -1 (-3700 3200)(-3275 3200);
WIRE 16 -1 (-3700 3250)(-3275 3250);
WIRE 16 -1 (-3700 3650)(-3275 3650);
WIRE 16 -1 (-3700 3350)(-3275 3350);
WIRE 16 -1 (-3700 3700)(-3275 3700);
WIRE 16 -1 (-3700 3400)(-3275 3400);
WIRE 16 -1 (-3700 3800)(-3275 3800);
WIRE 16 -1 (-3700 3450)(-3275 3450);
WIRE 16 -1 (-3700 3850)(-3275 3850);
WIRE 16 -1 (-3700 3500)(-3275 3500);
WIRE 16 -1 (-3700 5000)(-3275 5000);
WIRE 16 -1 (-3700 4400)(-3275 4400);
WIRE 16 -1 (-3700 5050)(-3275 5050);
WIRE 16 -1 (-3700 4450)(-3275 4450);
WIRE 16 -1 (-3700 4500)(-3275 4500);
WIRE 16 -1 (-3700 4550)(-3275 4550);
WIRE 16 -1 (-3700 4600)(-3275 4600);
WIRE 16 -1 (-3700 4100)(-3275 4100);
WIRE 16 -1 (-3700 4700)(-3275 4700);
WIRE 16 -1 (-3700 4150)(-3275 4150);
WIRE 16 -1 (-3700 4750)(-3275 4750);
WIRE 16 -1 (-3700 4800)(-3275 4800);
WIRE 16 -1 (-3700 4850)(-3275 4850);
WIRE 16 -1 (-3700 4250)(-3275 4250);
WIRE 16 -1 (-3700 4300)(-3275 4300);
WIRE 16 -1 (-3700 4900)(-3275 4900);
WIRE 16 -1 (-3700 4950)(-3275 4950);
WIRE 16 -1 (-3700 4350)(-3275 4350);
WIRE 16 -1 (-3700 5700)(-3275 5700);
WIRE 16 -1 (-3700 5750)(-3275 5750);
WIRE 16 -1 (-3700 5800)(-3275 5800);
WIRE 16 -1 (-3700 5150)(-3275 5150);
WIRE 16 -1 (-3700 5850)(-3275 5850);
WIRE 16 -1 (-3700 5200)(-3275 5200);
WIRE 16 -1 (-3700 5900)(-3275 5900);
WIRE 16 -1 (-3700 5250)(-3275 5250);
WIRE 16 -1 (-3700 5950)(-3275 5950);
WIRE 16 -1 (-3700 5300)(-3275 5300);
WIRE 16 -1 (-3700 5350)(-3275 5350);
WIRE 16 -1 (-3700 5400)(-3275 5400);
WIRE 16 -1 (-3700 5450)(-3275 5450);
WIRE 16 -1 (-3700 5500)(-3275 5500);
WIRE 16 -1 (-3700 5600)(-3275 5600);
WIRE 16 -1 (-3700 5650)(-3275 5650);
QUIT
